FILE_TYPE = MACRO_DRAWING;
SET COLOR_WIRE YELLOW;
SET COLOR_PROP ORANGE;
SET COLOR_DOT WHITE;
SET COLOR_ARC YELLOW;
SET COLOR_BODY GREEN;
SET COLOR_NOTE PURPLE;
SET PROP_DISPLAY VALUE;
SET PAGE_NUMBER P148;
FORCEADD Q_RES..2
(-2875 6050);
FORCEPROP 1 LAST LOCATION R1734
J 0
(-2830 6175);
DISPLAY 0.489362 (-2830 6175);
PAINT SKYBLUE (-2830 6175);
FORCEPROP 0 LAST $SEC 1
J 0
(-2825 6225);
PAINT MONO (-2825 6225);
DISPLAY INVISIBLE (-2825 6225);
FORCEPROP 0 LAST CDS_SEC 1
J 0
(-2825 6225);
PAINT MONO (-2825 6225);
DISPLAY INVISIBLE (-2825 6225);
FORCEPROP 1 LASTPIN (-2875 6150) $PN 1
J 0
(-2870 6112);
DISPLAY 0.489362 (-2870 6112);
PAINT GREEN (-2870 6112);
FORCEPROP 1 LASTPIN (-2875 5950) $PN 2
J 0
(-2870 5960);
DISPLAY 0.489362 (-2870 5960);
PAINT GREEN (-2870 5960);
FORCEPROP 1 LAST PACK_TYPE 0402LF
J 0
(-2835 5875);
DISPLAY 0.489362 (-2835 5875);
PAINT SKYBLUE (-2835 5875);
FORCEPROP 1 LAST MATERIAL CHIP
J 0
(-2835 5975);
DISPLAY 0.489362 (-2835 5975);
PAINT SKYBLUE (-2835 5975);
FORCEPROP 1 LAST TOLERANCE 1%
J 0
(-2830 6075);
DISPLAY 0.489362 (-2830 6075);
PAINT SKYBLUE (-2830 6075);
FORCEPROP 1 LAST VALUE 10K
J 0
(-2830 6125);
DISPLAY 0.489362 (-2830 6125);
PAINT SKYBLUE (-2830 6125);
FORCEPROP 1 LAST WATTAGE 1/16W
J 0
(-2835 6025);
DISPLAY 0.489362 (-2835 6025);
PAINT SKYBLUE (-2835 6025);
FORCEPROP 2 LAST CDS_LIB pure_quanta
J 0
(-2875 6050);
PAINT MONO (-2875 6050);
DISPLAY INVISIBLE (-2875 6050);
FORCEPROP 1 LAST PATH I244
J 0
(-2825 6225);
DISPLAY 0.978723 (-2825 6225);
PAINT WHITE (-2825 6225);
DISPLAY INVISIBLE (-2825 6225);
FORCEPROP 1 LAST PART_NUMBER CS31002FB08
J 0
(-2835 5925);
DISPLAY 0.489362 (-2835 5925);
PAINT SKYBLUE (-2835 5925);
DISPLAY INVISIBLE (-2835 5925);
FORCEADD Q_RES..2
(-3125 6050);
FORCEPROP 1 LAST LOCATION R1731
J 0
(-3080 6175);
DISPLAY 0.489362 (-3080 6175);
PAINT SKYBLUE (-3080 6175);
FORCEPROP 2 LAST $SEC 1
J 0
(-3075 6275);
DISPLAY 0.680851 (-3075 6275);
PAINT MONO (-3075 6275);
DISPLAY INVISIBLE (-3075 6275);
FORCEPROP 2 LAST CDS_SEC 1
J 0
(-3075 6275);
DISPLAY 0.680851 (-3075 6275);
DISPLAY INVISIBLE (-3075 6275);
FORCEPROP 1 LASTPIN (-3125 6150) $PN 1
J 0
(-3120 6112);
DISPLAY 0.489362 (-3120 6112);
FORCEPROP 1 LASTPIN (-3125 5950) $PN 2
J 0
(-3120 5960);
DISPLAY 0.489362 (-3120 5960);
FORCEPROP 1 LAST WATTAGE 1/16W
J 0
(-3085 6025);
DISPLAY 0.489362 (-3085 6025);
PAINT SKYBLUE (-3085 6025);
FORCEPROP 1 LAST VALUE 10K
J 0
(-3080 6125);
DISPLAY 0.489362 (-3080 6125);
PAINT SKYBLUE (-3080 6125);
FORCEPROP 1 LAST TOLERANCE 1%
J 0
(-3080 6075);
DISPLAY 0.489362 (-3080 6075);
PAINT SKYBLUE (-3080 6075);
FORCEPROP 1 LAST MATERIAL EMPTY
J 0
(-3085 5975);
DISPLAY 0.489362 (-3085 5975);
PAINT SKYBLUE (-3085 5975);
FORCEPROP 1 LAST PACK_TYPE 0402LF
J 0
(-3075 5925);
DISPLAY 0.489362 (-3075 5925);
PAINT SKYBLUE (-3075 5925);
FORCEPROP 2 LAST CDS_LIB pure_quanta
J 0
(-3125 6050);
DISPLAY INVISIBLE (-3125 6050);
FORCEPROP 1 LAST PATH I245
J 0
(-3075 6225);
DISPLAY 0.978723 (-3075 6225);
PAINT WHITE (-3075 6225);
DISPLAY INVISIBLE (-3075 6225);
FORCEPROP 1 LAST PART_NUMBER CS31002FB08
J 0
(-3085 5925);
DISPLAY 0.617021 (-3085 5925);
PAINT SKYBLUE (-3085 5925);
DISPLAY INVISIBLE (-3085 5925);
FORCEADD Q_RES..2
(-2875 5550);
FORCEPROP 1 LAST LOCATION R1735
J 0
(-2825 5575);
DISPLAY 0.489362 (-2825 5575);
PAINT SKYBLUE (-2825 5575);
FORCEPROP 2 LAST $SEC 1
J 0
(-2825 5775);
DISPLAY 0.680851 (-2825 5775);
PAINT MONO (-2825 5775);
DISPLAY INVISIBLE (-2825 5775);
FORCEPROP 2 LAST CDS_SEC 1
J 0
(-2825 5775);
DISPLAY 0.680851 (-2825 5775);
DISPLAY INVISIBLE (-2825 5775);
FORCEPROP 1 LASTPIN (-2875 5650) $PN 1
J 0
(-2870 5612);
DISPLAY 0.489362 (-2870 5612);
FORCEPROP 1 LASTPIN (-2875 5450) $PN 2
J 0
(-2870 5460);
DISPLAY 0.489362 (-2870 5460);
FORCEPROP 1 LAST MATERIAL EMPTY
J 0
(-2825 5425);
DISPLAY 0.489362 (-2825 5425);
PAINT RED (-2825 5425);
FORCEPROP 1 LAST VALUE 10K
J 0
(-2825 5525);
DISPLAY 0.489362 (-2825 5525);
PAINT SKYBLUE (-2825 5525);
FORCEPROP 1 LAST TOLERANCE 1%
J 0
(-2825 5475);
DISPLAY 0.489362 (-2825 5475);
PAINT SKYBLUE (-2825 5475);
FORCEPROP 2 LAST CDS_LIB pure_quanta
J 0
(-2875 5550);
DISPLAY INVISIBLE (-2875 5550);
FORCEPROP 1 LAST WATTAGE 1/16W
J 0
(-2835 5525);
DISPLAY 0.978723 (-2835 5525);
PAINT SKYBLUE (-2835 5525);
DISPLAY INVISIBLE (-2835 5525);
FORCEPROP 1 LAST PACK_TYPE 0402LF
J 0
(-2835 5375);
DISPLAY 0.978723 (-2835 5375);
PAINT SKYBLUE (-2835 5375);
DISPLAY INVISIBLE (-2835 5375);
FORCEPROP 1 LAST PATH I246
J 0
(-2825 5725);
DISPLAY 0.978723 (-2825 5725);
PAINT WHITE (-2825 5725);
DISPLAY INVISIBLE (-2825 5725);
FORCEPROP 1 LAST PART_NUMBER CS31002FB08
J 0
(-2835 5425);
DISPLAY 0.978723 (-2835 5425);
PAINT SKYBLUE (-2835 5425);
DISPLAY INVISIBLE (-2835 5425);
FORCEADD UNIVERSAL_GND..1
(-2875 5325);
FORCEPROP 3 LASTPIN (-2875 5375) SIG_NAME GND\g
J 0
(-2865 5385);
DISPLAY 0.659574 (-2865 5385);
PAINT MONO (-2865 5385);
DISPLAY INVISIBLE (-2865 5385);
FORCEPROP 2 LAST CDS_LIB pure_quanta_power
J 0
(-2875 5325);
DISPLAY INVISIBLE (-2875 5325);
FORCEPROP 1 LAST HDL_POWER GND
J 1
(-2850 5250);
DISPLAY 0.872340 (-2850 5250);
PAINT GREEN (-2850 5250);
DISPLAY INVISIBLE (-2850 5250);
FORCEPROP 1 LAST PATH I247
J 0
(-2800 5325);
DISPLAY 0.872340 (-2800 5325);
PAINT AQUA (-2800 5325);
DISPLAY INVISIBLE (-2800 5325);
FORCEADD UNIVERSAL_POWER..1
(-3525 6400);
FORCEPROP 3 LASTPIN (-3525 6350) SIG_NAME P3V3_AUX\g
J 0
(-3515 6360);
DISPLAY 0.659574 (-3515 6360);
PAINT MONO (-3515 6360);
DISPLAY INVISIBLE (-3515 6360);
FORCEPROP 1 LAST HDL_POWER P3V3_AUX
J 1
(-3525 6450);
DISPLAY 0.489362 (-3525 6450);
PAINT GREEN (-3525 6450);
FORCEPROP 2 LAST CDS_LIB pure_quanta_power
J 0
(-3525 6400);
DISPLAY INVISIBLE (-3525 6400);
FORCEPROP 1 LAST PATH I248
J 0
(-3475 6425);
DISPLAY 0.872340 (-3475 6425);
PAINT AQUA (-3475 6425);
DISPLAY INVISIBLE (-3475 6425);
FORCEADD Q_RES..2
(-3325 6050);
FORCEPROP 1 LAST LOCATION R1728
J 0
(-3275 6175);
DISPLAY 0.489362 (-3275 6175);
PAINT SKYBLUE (-3275 6175);
FORCEPROP 2 LAST $SEC 1
J 0
(-3275 6275);
DISPLAY 0.680851 (-3275 6275);
PAINT MONO (-3275 6275);
DISPLAY INVISIBLE (-3275 6275);
FORCEPROP 2 LAST CDS_SEC 1
J 0
(-3275 6275);
DISPLAY 0.680851 (-3275 6275);
DISPLAY INVISIBLE (-3275 6275);
FORCEPROP 1 LASTPIN (-3325 6150) $PN 1
J 0
(-3320 6112);
DISPLAY 0.489362 (-3320 6112);
FORCEPROP 1 LASTPIN (-3325 5950) $PN 2
J 0
(-3320 5960);
DISPLAY 0.489362 (-3320 5960);
FORCEPROP 1 LAST VALUE 10K
J 0
(-3275 6125);
DISPLAY 0.489362 (-3275 6125);
PAINT SKYBLUE (-3275 6125);
FORCEPROP 1 LAST TOLERANCE 1%
J 0
(-3275 6075);
DISPLAY 0.489362 (-3275 6075);
PAINT SKYBLUE (-3275 6075);
FORCEPROP 1 LAST MATERIAL EMPTY
J 0
(-3285 5975);
DISPLAY 0.510638 (-3285 5975);
PAINT SKYBLUE (-3285 5975);
FORCEPROP 1 LAST PACK_TYPE 0402LF
J 0
(-3285 5875);
DISPLAY 0.978723 (-3285 5875);
PAINT SKYBLUE (-3285 5875);
DISPLAY INVISIBLE (-3285 5875);
FORCEPROP 1 LAST WATTAGE 1/16W
J 0
(-3285 6025);
DISPLAY 0.978723 (-3285 6025);
PAINT SKYBLUE (-3285 6025);
DISPLAY INVISIBLE (-3285 6025);
FORCEPROP 2 LAST CDS_LIB pure_quanta
J 0
(-3325 6050);
DISPLAY INVISIBLE (-3325 6050);
FORCEPROP 1 LAST PATH I249
J 0
(-3275 6225);
DISPLAY 0.978723 (-3275 6225);
PAINT WHITE (-3275 6225);
DISPLAY INVISIBLE (-3275 6225);
FORCEPROP 1 LAST PART_NUMBER CS31002FB08
J 0
(-3285 5925);
DISPLAY 0.978723 (-3285 5925);
PAINT SKYBLUE (-3285 5925);
DISPLAY INVISIBLE (-3285 5925);
FORCEADD Q_RES..2
(-3525 6050);
FORCEPROP 1 LAST LOCATION R1727
J 0
(-3475 6175);
DISPLAY 0.489362 (-3475 6175);
PAINT SKYBLUE (-3475 6175);
FORCEPROP 2 LAST $SEC 1
J 0
(-3475 6275);
DISPLAY 0.680851 (-3475 6275);
PAINT MONO (-3475 6275);
DISPLAY INVISIBLE (-3475 6275);
FORCEPROP 2 LAST CDS_SEC 1
J 0
(-3475 6275);
DISPLAY 0.680851 (-3475 6275);
DISPLAY INVISIBLE (-3475 6275);
FORCEPROP 1 LASTPIN (-3525 6150) $PN 1
J 0
(-3520 6112);
DISPLAY 0.489362 (-3520 6112);
FORCEPROP 1 LASTPIN (-3525 5950) $PN 2
J 0
(-3520 5960);
DISPLAY 0.489362 (-3520 5960);
FORCEPROP 1 LAST TOLERANCE 1%
J 0
(-3475 6075);
DISPLAY 0.489362 (-3475 6075);
PAINT SKYBLUE (-3475 6075);
FORCEPROP 1 LAST MATERIAL EMPTY
J 0
(-3485 5975);
DISPLAY 0.510638 (-3485 5975);
PAINT SKYBLUE (-3485 5975);
FORCEPROP 1 LAST VALUE 10K
J 0
(-3475 6125);
DISPLAY 0.489362 (-3475 6125);
PAINT SKYBLUE (-3475 6125);
FORCEPROP 1 LAST PACK_TYPE 0402LF
J 0
(-3485 5875);
DISPLAY 0.978723 (-3485 5875);
PAINT SKYBLUE (-3485 5875);
DISPLAY INVISIBLE (-3485 5875);
FORCEPROP 1 LAST WATTAGE 1/16W
J 0
(-3485 6025);
DISPLAY 0.978723 (-3485 6025);
PAINT SKYBLUE (-3485 6025);
DISPLAY INVISIBLE (-3485 6025);
FORCEPROP 2 LAST CDS_LIB pure_quanta
J 0
(-3525 6050);
DISPLAY INVISIBLE (-3525 6050);
FORCEPROP 1 LAST PATH I250
J 0
(-3475 6225);
DISPLAY 0.978723 (-3475 6225);
PAINT WHITE (-3475 6225);
DISPLAY INVISIBLE (-3475 6225);
FORCEPROP 1 LAST PART_NUMBER CS31002FB08
J 0
(-3485 5925);
DISPLAY 0.978723 (-3485 5925);
PAINT SKYBLUE (-3485 5925);
DISPLAY INVISIBLE (-3485 5925);
FORCEADD OFFPAGE..2
R 2
(-4175 5850);
FORCEPROP 2 LAST $XR0 151 
J 0
(-4430 5850);
DISPLAY 0.638298 (-4430 5850);
PAINT MONO (-4430 5850);
FORCEPROP 2 LAST $XR1 171 
J 0
(-4550 5850);
DISPLAY 0.638298 (-4550 5850);
PAINT MONO (-4550 5850);
FORCEPROP 2 LAST CDS_LIB standard
J 0
(-4175 5850);
DISPLAY INVISIBLE (-4175 5850);
FORCEPROP 1 LAST OFFPAGE TRUE
J 2
(-4500 5725);
DISPLAY 0.872340 (-4500 5725);
PAINT GREEN (-4500 5725);
DISPLAY INVISIBLE (-4500 5725);
FORCEPROP 1 LAST COMMENT_BODY TRUE
J 2
(-4130 5755);
DISPLAY 0.872340 (-4130 5755);
PAINT GREEN (-4130 5755);
DISPLAY INVISIBLE (-4130 5755);
FORCEPROP 2 LAST PATH I251
J 0
(-4450 5900);
DISPLAY 1.021277 (-4450 5900);
DISPLAY INVISIBLE (-4450 5900);
FORCEADD OFFPAGE..2
R 2
(-4175 5800);
FORCEPROP 2 LAST $XR0 171 
J 0
(-4430 5800);
DISPLAY 0.638298 (-4430 5800);
PAINT MONO (-4430 5800);
FORCEPROP 2 LAST $XR1 151 
J 0
(-4550 5800);
DISPLAY 0.638298 (-4550 5800);
PAINT MONO (-4550 5800);
FORCEPROP 2 LAST CDS_LIB standard
J 0
(-4175 5800);
DISPLAY INVISIBLE (-4175 5800);
FORCEPROP 1 LAST OFFPAGE TRUE
J 2
(-4500 5675);
DISPLAY 0.872340 (-4500 5675);
PAINT GREEN (-4500 5675);
DISPLAY INVISIBLE (-4500 5675);
FORCEPROP 1 LAST COMMENT_BODY TRUE
J 2
(-4130 5705);
DISPLAY 0.872340 (-4130 5705);
PAINT GREEN (-4130 5705);
DISPLAY INVISIBLE (-4130 5705);
FORCEPROP 2 LAST PATH I252
J 0
(-4450 5850);
DISPLAY 1.021277 (-4450 5850);
DISPLAY INVISIBLE (-4450 5850);
FORCEADD OFFPAGE..2
R 2
(-4175 5750);
FORCEPROP 2 LAST $XR0 150 
J 0
(-4430 5750);
DISPLAY 0.638298 (-4430 5750);
PAINT MONO (-4430 5750);
FORCEPROP 2 LAST $XR1 171 
J 0
(-4550 5750);
DISPLAY 0.638298 (-4550 5750);
PAINT MONO (-4550 5750);
FORCEPROP 2 LAST CDS_LIB standard
J 0
(-4175 5750);
DISPLAY INVISIBLE (-4175 5750);
FORCEPROP 1 LAST OFFPAGE TRUE
J 2
(-4500 5625);
DISPLAY 0.872340 (-4500 5625);
PAINT GREEN (-4500 5625);
DISPLAY INVISIBLE (-4500 5625);
FORCEPROP 1 LAST COMMENT_BODY TRUE
J 2
(-4130 5655);
DISPLAY 0.872340 (-4130 5655);
PAINT GREEN (-4130 5655);
DISPLAY INVISIBLE (-4130 5655);
FORCEPROP 2 LAST PATH I253
J 0
(-4450 5800);
DISPLAY 1.021277 (-4450 5800);
DISPLAY INVISIBLE (-4450 5800);
FORCEADD OFFPAGE..2
R 2
(-4175 5700);
FORCEPROP 2 LAST $XR0 150 
J 0
(-4430 5700);
DISPLAY 0.638298 (-4430 5700);
PAINT MONO (-4430 5700);
FORCEPROP 2 LAST $XR1 171 
J 0
(-4550 5700);
DISPLAY 0.638298 (-4550 5700);
PAINT MONO (-4550 5700);
FORCEPROP 2 LAST CDS_LIB standard
J 0
(-4175 5700);
DISPLAY INVISIBLE (-4175 5700);
FORCEPROP 1 LAST OFFPAGE TRUE
J 2
(-4500 5575);
DISPLAY 0.872340 (-4500 5575);
PAINT GREEN (-4500 5575);
DISPLAY INVISIBLE (-4500 5575);
FORCEPROP 1 LAST COMMENT_BODY TRUE
J 2
(-4130 5605);
DISPLAY 0.872340 (-4130 5605);
PAINT GREEN (-4130 5605);
DISPLAY INVISIBLE (-4130 5605);
FORCEPROP 2 LAST PATH I254
J 0
(-4450 5750);
DISPLAY 1.021277 (-4450 5750);
DISPLAY INVISIBLE (-4450 5750);
FORCEADD Q_RES..2
(-450 6025);
FORCEPROP 1 LAST LOCATION R1747
J 0
(-405 6150);
DISPLAY 0.489362 (-405 6150);
PAINT SKYBLUE (-405 6150);
FORCEPROP 0 LAST $SEC 1
J 0
(-400 6200);
PAINT MONO (-400 6200);
DISPLAY INVISIBLE (-400 6200);
FORCEPROP 0 LAST CDS_SEC 1
J 0
(-400 6200);
PAINT MONO (-400 6200);
DISPLAY INVISIBLE (-400 6200);
FORCEPROP 1 LASTPIN (-450 6125) $PN 1
J 0
(-445 6087);
DISPLAY 0.489362 (-445 6087);
PAINT GREEN (-445 6087);
FORCEPROP 1 LASTPIN (-450 5925) $PN 2
J 0
(-445 5935);
DISPLAY 0.489362 (-445 5935);
PAINT GREEN (-445 5935);
FORCEPROP 1 LAST WATTAGE 1/16W
J 0
(-410 6000);
DISPLAY 0.489362 (-410 6000);
PAINT SKYBLUE (-410 6000);
FORCEPROP 1 LAST MATERIAL CHIP
J 0
(-410 5950);
DISPLAY 0.489362 (-410 5950);
PAINT SKYBLUE (-410 5950);
FORCEPROP 1 LAST TOLERANCE 1%
J 0
(-405 6050);
DISPLAY 0.489362 (-405 6050);
PAINT SKYBLUE (-405 6050);
FORCEPROP 1 LAST VALUE 10K
J 0
(-405 6100);
DISPLAY 0.489362 (-405 6100);
PAINT SKYBLUE (-405 6100);
FORCEPROP 1 LAST PACK_TYPE 0402LF
J 0
(-410 5850);
DISPLAY 0.489362 (-410 5850);
PAINT SKYBLUE (-410 5850);
FORCEPROP 2 LAST CDS_LIB pure_quanta
J 0
(-450 6025);
PAINT MONO (-450 6025);
DISPLAY INVISIBLE (-450 6025);
FORCEPROP 1 LAST PATH I255
J 0
(-400 6200);
DISPLAY 0.978723 (-400 6200);
PAINT WHITE (-400 6200);
DISPLAY INVISIBLE (-400 6200);
FORCEPROP 1 LAST PART_NUMBER CS31002FB08
J 0
(-410 5900);
DISPLAY 0.489362 (-410 5900);
PAINT SKYBLUE (-410 5900);
DISPLAY INVISIBLE (-410 5900);
FORCEADD Q_RES..2
(-675 6025);
FORCEPROP 1 LAST LOCATION R1746
J 0
(-630 6150);
DISPLAY 0.489362 (-630 6150);
PAINT SKYBLUE (-630 6150);
FORCEPROP 2 LAST $SEC 1
J 0
(-625 6250);
DISPLAY 0.680851 (-625 6250);
PAINT MONO (-625 6250);
DISPLAY INVISIBLE (-625 6250);
FORCEPROP 2 LAST CDS_SEC 1
J 0
(-625 6250);
DISPLAY 0.680851 (-625 6250);
DISPLAY INVISIBLE (-625 6250);
FORCEPROP 1 LASTPIN (-675 6125) $PN 1
J 0
(-670 6087);
DISPLAY 0.489362 (-670 6087);
FORCEPROP 1 LASTPIN (-675 5925) $PN 2
J 0
(-670 5935);
DISPLAY 0.489362 (-670 5935);
FORCEPROP 1 LAST WATTAGE 1/16W
J 0
(-635 6000);
DISPLAY 0.489362 (-635 6000);
PAINT SKYBLUE (-635 6000);
FORCEPROP 1 LAST MATERIAL CHIP
J 0
(-635 5950);
DISPLAY 0.489362 (-635 5950);
PAINT SKYBLUE (-635 5950);
FORCEPROP 1 LAST TOLERANCE 1%
J 0
(-630 6050);
DISPLAY 0.489362 (-630 6050);
PAINT SKYBLUE (-630 6050);
FORCEPROP 1 LAST VALUE 10K
J 0
(-630 6100);
DISPLAY 0.489362 (-630 6100);
PAINT SKYBLUE (-630 6100);
FORCEPROP 1 LAST PACK_TYPE 0402LF
J 0
(-625 5900);
DISPLAY 0.489362 (-625 5900);
PAINT SKYBLUE (-625 5900);
FORCEPROP 2 LAST CDS_LIB pure_quanta
J 0
(-675 6025);
DISPLAY INVISIBLE (-675 6025);
FORCEPROP 1 LAST PATH I256
J 0
(-625 6200);
DISPLAY 0.978723 (-625 6200);
PAINT WHITE (-625 6200);
DISPLAY INVISIBLE (-625 6200);
FORCEPROP 1 LAST PART_NUMBER CS31002FB08
J 0
(-635 5900);
DISPLAY 0.617021 (-635 5900);
PAINT SKYBLUE (-635 5900);
DISPLAY INVISIBLE (-635 5900);
FORCEADD Q_RES..2
(-875 6025);
FORCEPROP 1 LAST LOCATION R1745
J 0
(-825 6150);
DISPLAY 0.489362 (-825 6150);
PAINT SKYBLUE (-825 6150);
FORCEPROP 2 LAST $SEC 1
J 0
(-825 6250);
DISPLAY 0.680851 (-825 6250);
PAINT MONO (-825 6250);
DISPLAY INVISIBLE (-825 6250);
FORCEPROP 2 LAST CDS_SEC 1
J 0
(-825 6250);
DISPLAY 0.680851 (-825 6250);
DISPLAY INVISIBLE (-825 6250);
FORCEPROP 1 LASTPIN (-875 6125) $PN 1
J 0
(-870 6087);
DISPLAY 0.489362 (-870 6087);
FORCEPROP 1 LASTPIN (-875 5925) $PN 2
J 0
(-870 5935);
DISPLAY 0.489362 (-870 5935);
FORCEPROP 1 LAST TOLERANCE 1%
J 0
(-825 6050);
DISPLAY 0.489362 (-825 6050);
PAINT SKYBLUE (-825 6050);
FORCEPROP 1 LAST VALUE 10K
J 0
(-825 6100);
DISPLAY 0.489362 (-825 6100);
PAINT SKYBLUE (-825 6100);
FORCEPROP 2 LAST CDS_LIB pure_quanta
J 0
(-875 6025);
DISPLAY INVISIBLE (-875 6025);
FORCEPROP 1 LAST WATTAGE 1/16W
J 0
(-835 6000);
DISPLAY 0.978723 (-835 6000);
PAINT SKYBLUE (-835 6000);
DISPLAY INVISIBLE (-835 6000);
FORCEPROP 1 LAST MATERIAL CHIP
J 0
(-835 5950);
DISPLAY 0.978723 (-835 5950);
PAINT SKYBLUE (-835 5950);
DISPLAY INVISIBLE (-835 5950);
FORCEPROP 1 LAST PACK_TYPE 0402LF
J 0
(-835 5850);
DISPLAY 0.978723 (-835 5850);
PAINT SKYBLUE (-835 5850);
DISPLAY INVISIBLE (-835 5850);
FORCEPROP 1 LAST PATH I257
J 0
(-825 6200);
DISPLAY 0.978723 (-825 6200);
PAINT WHITE (-825 6200);
DISPLAY INVISIBLE (-825 6200);
FORCEPROP 1 LAST PART_NUMBER CS31002FB08
J 0
(-835 5900);
DISPLAY 0.978723 (-835 5900);
PAINT SKYBLUE (-835 5900);
DISPLAY INVISIBLE (-835 5900);
FORCEADD Q_RES..2
(-450 5525);
FORCEPROP 1 LAST LOCATION R1748
J 0
(-400 5550);
DISPLAY 0.489362 (-400 5550);
PAINT SKYBLUE (-400 5550);
FORCEPROP 2 LAST $SEC 1
J 0
(-400 5750);
DISPLAY 0.680851 (-400 5750);
PAINT MONO (-400 5750);
DISPLAY INVISIBLE (-400 5750);
FORCEPROP 2 LAST CDS_SEC 1
J 0
(-400 5750);
DISPLAY 0.680851 (-400 5750);
DISPLAY INVISIBLE (-400 5750);
FORCEPROP 1 LASTPIN (-450 5625) $PN 1
J 0
(-445 5587);
DISPLAY 0.489362 (-445 5587);
FORCEPROP 1 LASTPIN (-450 5425) $PN 2
J 0
(-445 5435);
DISPLAY 0.489362 (-445 5435);
FORCEPROP 1 LAST MATERIAL EMPTY
J 0
(-400 5400);
DISPLAY 0.489362 (-400 5400);
PAINT RED (-400 5400);
FORCEPROP 1 LAST TOLERANCE 1%
J 0
(-400 5450);
DISPLAY 0.489362 (-400 5450);
PAINT SKYBLUE (-400 5450);
FORCEPROP 1 LAST VALUE 10K
J 0
(-400 5500);
DISPLAY 0.489362 (-400 5500);
PAINT SKYBLUE (-400 5500);
FORCEPROP 2 LAST CDS_LIB pure_quanta
J 0
(-450 5525);
DISPLAY INVISIBLE (-450 5525);
FORCEPROP 1 LAST WATTAGE 1/16W
J 0
(-410 5500);
DISPLAY 0.978723 (-410 5500);
PAINT SKYBLUE (-410 5500);
DISPLAY INVISIBLE (-410 5500);
FORCEPROP 1 LAST PACK_TYPE 0402LF
J 0
(-410 5350);
DISPLAY 0.978723 (-410 5350);
PAINT SKYBLUE (-410 5350);
DISPLAY INVISIBLE (-410 5350);
FORCEPROP 1 LAST PATH I258
J 0
(-400 5700);
DISPLAY 0.978723 (-400 5700);
PAINT WHITE (-400 5700);
DISPLAY INVISIBLE (-400 5700);
FORCEPROP 1 LAST PART_NUMBER CS31002FB08
J 0
(-410 5400);
DISPLAY 0.978723 (-410 5400);
PAINT SKYBLUE (-410 5400);
DISPLAY INVISIBLE (-410 5400);
FORCEADD UNIVERSAL_GND..1
(-450 5300);
FORCEPROP 3 LASTPIN (-450 5350) SIG_NAME GND\g
J 0
(-440 5360);
DISPLAY 0.659574 (-440 5360);
PAINT MONO (-440 5360);
DISPLAY INVISIBLE (-440 5360);
FORCEPROP 2 LAST CDS_LIB pure_quanta_power
J 0
(-450 5300);
DISPLAY INVISIBLE (-450 5300);
FORCEPROP 1 LAST HDL_POWER GND
J 1
(-425 5225);
DISPLAY 0.872340 (-425 5225);
PAINT GREEN (-425 5225);
DISPLAY INVISIBLE (-425 5225);
FORCEPROP 1 LAST PATH I259
J 0
(-375 5300);
DISPLAY 0.872340 (-375 5300);
PAINT AQUA (-375 5300);
DISPLAY INVISIBLE (-375 5300);
FORCEADD UNIVERSAL_POWER..1
(-1075 6375);
FORCEPROP 3 LASTPIN (-1075 6325) SIG_NAME P3V3_AUX\g
J 0
(-1065 6335);
DISPLAY 0.659574 (-1065 6335);
PAINT MONO (-1065 6335);
DISPLAY INVISIBLE (-1065 6335);
FORCEPROP 1 LAST HDL_POWER P3V3_AUX
J 1
(-1075 6425);
DISPLAY 0.489362 (-1075 6425);
PAINT GREEN (-1075 6425);
FORCEPROP 2 LAST CDS_LIB pure_quanta_power
J 0
(-1075 6375);
DISPLAY INVISIBLE (-1075 6375);
FORCEPROP 1 LAST PATH I260
J 0
(-1025 6400);
DISPLAY 0.872340 (-1025 6400);
PAINT AQUA (-1025 6400);
DISPLAY INVISIBLE (-1025 6400);
FORCEADD Q_RES..2
(-1075 6025);
FORCEPROP 1 LAST LOCATION R1744
J 0
(-1025 6150);
DISPLAY 0.489362 (-1025 6150);
PAINT SKYBLUE (-1025 6150);
FORCEPROP 2 LAST $SEC 1
J 0
(-1025 6250);
DISPLAY 0.680851 (-1025 6250);
PAINT MONO (-1025 6250);
DISPLAY INVISIBLE (-1025 6250);
FORCEPROP 2 LAST CDS_SEC 1
J 0
(-1025 6250);
DISPLAY 0.680851 (-1025 6250);
DISPLAY INVISIBLE (-1025 6250);
FORCEPROP 1 LASTPIN (-1075 6125) $PN 1
J 0
(-1070 6087);
DISPLAY 0.489362 (-1070 6087);
FORCEPROP 1 LASTPIN (-1075 5925) $PN 2
J 0
(-1070 5935);
DISPLAY 0.489362 (-1070 5935);
FORCEPROP 1 LAST TOLERANCE 1%
J 0
(-1025 6050);
DISPLAY 0.489362 (-1025 6050);
PAINT SKYBLUE (-1025 6050);
FORCEPROP 1 LAST VALUE 10K
J 0
(-1025 6100);
DISPLAY 0.489362 (-1025 6100);
PAINT SKYBLUE (-1025 6100);
FORCEPROP 2 LAST CDS_LIB pure_quanta
J 0
(-1075 6025);
DISPLAY INVISIBLE (-1075 6025);
FORCEPROP 1 LAST WATTAGE 1/16W
J 0
(-1035 6000);
DISPLAY 0.978723 (-1035 6000);
PAINT SKYBLUE (-1035 6000);
DISPLAY INVISIBLE (-1035 6000);
FORCEPROP 1 LAST MATERIAL CHIP
J 0
(-1035 5950);
DISPLAY 0.978723 (-1035 5950);
PAINT SKYBLUE (-1035 5950);
DISPLAY INVISIBLE (-1035 5950);
FORCEPROP 1 LAST PACK_TYPE 0402LF
J 0
(-1035 5850);
DISPLAY 0.978723 (-1035 5850);
PAINT SKYBLUE (-1035 5850);
DISPLAY INVISIBLE (-1035 5850);
FORCEPROP 1 LAST PATH I261
J 0
(-1025 6200);
DISPLAY 0.978723 (-1025 6200);
PAINT WHITE (-1025 6200);
DISPLAY INVISIBLE (-1025 6200);
FORCEPROP 1 LAST PART_NUMBER CS31002FB08
J 0
(-1035 5900);
DISPLAY 0.978723 (-1035 5900);
PAINT SKYBLUE (-1035 5900);
DISPLAY INVISIBLE (-1035 5900);
FORCEADD OFFPAGE..2
R 2
(-2000 5825);
FORCEPROP 2 LAST $XR0 172 
J 0
(-2285 5825);
DISPLAY 0.638298 (-2285 5825);
PAINT MONO (-2285 5825);
FORCEPROP 2 LAST $XR1 171 
J 0
(-2405 5825);
DISPLAY 0.638298 (-2405 5825);
PAINT MONO (-2405 5825);
FORCEPROP 2 LAST CDS_LIB standard
J 0
(-2000 5825);
DISPLAY INVISIBLE (-2000 5825);
FORCEPROP 1 LAST OFFPAGE TRUE
J 2
(-2325 5700);
DISPLAY 0.872340 (-2325 5700);
PAINT GREEN (-2325 5700);
DISPLAY INVISIBLE (-2325 5700);
FORCEPROP 1 LAST COMMENT_BODY TRUE
J 2
(-1955 5730);
DISPLAY 0.872340 (-1955 5730);
PAINT GREEN (-1955 5730);
DISPLAY INVISIBLE (-1955 5730);
FORCEPROP 2 LAST PATH I262
J 0
(-2250 5875);
DISPLAY 1.021277 (-2250 5875);
DISPLAY INVISIBLE (-2250 5875);
FORCEADD OFFPAGE..2
R 2
(-2000 5775);
FORCEPROP 2 LAST $XR0 171 
J 0
(-2285 5775);
DISPLAY 0.638298 (-2285 5775);
PAINT MONO (-2285 5775);
FORCEPROP 2 LAST $XR1 172 
J 0
(-2405 5775);
DISPLAY 0.638298 (-2405 5775);
PAINT MONO (-2405 5775);
FORCEPROP 2 LAST CDS_LIB standard
J 0
(-2000 5775);
DISPLAY INVISIBLE (-2000 5775);
FORCEPROP 1 LAST OFFPAGE TRUE
J 2
(-2325 5650);
DISPLAY 0.872340 (-2325 5650);
PAINT GREEN (-2325 5650);
DISPLAY INVISIBLE (-2325 5650);
FORCEPROP 1 LAST COMMENT_BODY TRUE
J 2
(-1955 5680);
DISPLAY 0.872340 (-1955 5680);
PAINT GREEN (-1955 5680);
DISPLAY INVISIBLE (-1955 5680);
FORCEPROP 2 LAST PATH I263
J 0
(-2250 5825);
DISPLAY 1.021277 (-2250 5825);
DISPLAY INVISIBLE (-2250 5825);
FORCEADD OFFPAGE..2
R 2
(-2000 5725);
FORCEPROP 2 LAST $XR1 172 
J 0
(-2405 5725);
DISPLAY 0.638298 (-2405 5725);
PAINT MONO (-2405 5725);
FORCEPROP 2 LAST $XR0 171 
J 0
(-2285 5725);
DISPLAY 0.638298 (-2285 5725);
PAINT MONO (-2285 5725);
FORCEPROP 2 LAST CDS_LIB standard
J 0
(-2000 5725);
DISPLAY INVISIBLE (-2000 5725);
FORCEPROP 1 LAST OFFPAGE TRUE
J 2
(-2325 5600);
DISPLAY 0.872340 (-2325 5600);
PAINT GREEN (-2325 5600);
DISPLAY INVISIBLE (-2325 5600);
FORCEPROP 1 LAST COMMENT_BODY TRUE
J 2
(-1955 5630);
DISPLAY 0.872340 (-1955 5630);
PAINT GREEN (-1955 5630);
DISPLAY INVISIBLE (-1955 5630);
FORCEPROP 2 LAST PATH I264
J 0
(-2250 5775);
DISPLAY 1.021277 (-2250 5775);
DISPLAY INVISIBLE (-2250 5775);
FORCEADD OFFPAGE..2
R 2
(-2000 5675);
FORCEPROP 2 LAST $XR0 171 
J 0
(-2285 5675);
DISPLAY 0.638298 (-2285 5675);
PAINT MONO (-2285 5675);
FORCEPROP 2 LAST $XR1 172 
J 0
(-2405 5675);
DISPLAY 0.638298 (-2405 5675);
PAINT MONO (-2405 5675);
FORCEPROP 2 LAST CDS_LIB standard
J 0
(-2000 5675);
DISPLAY INVISIBLE (-2000 5675);
FORCEPROP 1 LAST OFFPAGE TRUE
J 2
(-2325 5550);
DISPLAY 0.872340 (-2325 5550);
PAINT GREEN (-2325 5550);
DISPLAY INVISIBLE (-2325 5550);
FORCEPROP 1 LAST COMMENT_BODY TRUE
J 2
(-1955 5580);
DISPLAY 0.872340 (-1955 5580);
PAINT GREEN (-1955 5580);
DISPLAY INVISIBLE (-1955 5580);
FORCEPROP 2 LAST PATH I265
J 0
(-2250 5725);
DISPLAY 1.021277 (-2250 5725);
DISPLAY INVISIBLE (-2250 5725);
FORCEADD 74LV4052PW..1
(-4875 4050);
FORCEPROP 1 LAST LOCATION U160
J 0
(-5050 4625);
DISPLAY 0.723404 (-5050 4625);
PAINT GREEN (-5050 4625);
FORCEPROP 2 LAST SEC 1
J 0
(-5050 4800);
DISPLAY 0.680851 (-5050 4800);
PAINT MONO (-5050 4800);
DISPLAY INVISIBLE (-5050 4800);
FORCEPROP 2 LASTPIN (-4550 4175) $PN 12
J 0
(-4540 4185);
DISPLAY 0.680851 (-4540 4185);
PAINT MONO (-4540 4185);
FORCEPROP 2 LASTPIN (-4550 4225) $PN 14
J 0
(-4540 4235);
DISPLAY 0.680851 (-4540 4235);
PAINT MONO (-4540 4235);
FORCEPROP 2 LASTPIN (-4550 4275) $PN 15
J 0
(-4540 4285);
DISPLAY 0.680851 (-4540 4285);
PAINT MONO (-4540 4285);
FORCEPROP 2 LASTPIN (-4550 4325) $PN 11
J 0
(-4540 4335);
DISPLAY 0.680851 (-4540 4335);
PAINT MONO (-4540 4335);
FORCEPROP 2 LASTPIN (-5200 4275) $PN 13
J 2
(-5210 4285);
DISPLAY 0.680851 (-5210 4285);
PAINT MONO (-5210 4285);
FORCEPROP 2 LASTPIN (-4550 3925) $PN 1
J 0
(-4540 3935);
DISPLAY 0.680851 (-4540 3935);
PAINT MONO (-4540 3935);
FORCEPROP 2 LASTPIN (-4550 3975) $PN 5
J 0
(-4540 3985);
DISPLAY 0.680851 (-4540 3985);
PAINT MONO (-4540 3985);
FORCEPROP 2 LASTPIN (-4550 4025) $PN 2
J 0
(-4540 4035);
DISPLAY 0.680851 (-4540 4035);
PAINT MONO (-4540 4035);
FORCEPROP 2 LASTPIN (-4550 4075) $PN 4
J 0
(-4540 4085);
DISPLAY 0.680851 (-4540 4085);
PAINT MONO (-4540 4085);
FORCEPROP 2 LASTPIN (-5200 4075) $PN 3
J 2
(-5210 4085);
DISPLAY 0.680851 (-5210 4085);
PAINT MONO (-5210 4085);
FORCEPROP 2 LASTPIN (-5200 3825) $PN 6
J 2
(-5210 3835);
DISPLAY 0.680851 (-5210 3835);
PAINT MONO (-5210 3835);
FORCEPROP 2 LASTPIN (-4550 3775) $PN 8
J 0
(-4540 3785);
DISPLAY 0.680851 (-4540 3785);
PAINT MONO (-4540 3785);
FORCEPROP 2 LASTPIN (-5200 3875) $PN 10
J 2
(-5210 3885);
DISPLAY 0.680851 (-5210 3885);
PAINT MONO (-5210 3885);
FORCEPROP 2 LASTPIN (-5200 3925) $PN 9
J 2
(-5210 3935);
DISPLAY 0.680851 (-5210 3935);
PAINT MONO (-5210 3935);
FORCEPROP 2 LASTPIN (-5200 4325) $PN 16
J 2
(-5210 4335);
DISPLAY 0.680851 (-5210 4335);
PAINT MONO (-5210 4335);
FORCEPROP 2 LASTPIN (-4550 3825) $PN 7
J 0
(-4540 3835);
DISPLAY 0.680851 (-4540 3835);
PAINT MONO (-4540 3835);
FORCEPROP 1 LAST MATERIAL IC
J 0
(-5044 4432);
DISPLAY 0.723404 (-5044 4432);
PAINT GREEN (-5044 4432);
FORCEPROP 2 LAST PART_TYPE SMLF
J 0
(-5050 4750);
DISPLAY 1.021277 (-5050 4750);
FORCEPROP 2 LAST VALUE 74LV4052PW
J 0
(-5050 4700);
DISPLAY 0.489362 (-5050 4700);
PAINT SKYBLUE (-5050 4700);
FORCEPROP 2 LAST SEC_TYPE 
J 0
(-5050 4800);
DISPLAY 0.680851 (-5050 4800);
DISPLAY INVISIBLE (-5050 4800);
FORCEPROP 2 LAST CDS_LIB pure_quanta
J 0
(-4875 4050);
DISPLAY INVISIBLE (-4875 4050);
FORCEPROP 1 LAST CDS_LMAN_SYM_OUTLINE -175,325,175,-325
J 0
(-4875 4050);
DISPLAY 0.468085 (-4875 4050);
PAINT GREEN (-4875 4050);
DISPLAY INVISIBLE (-4875 4050);
FORCEPROP 1 LAST NEEDS_NO_SIZE TRUE
J 0
(-4875 4050);
DISPLAY 0.723404 (-4875 4050);
PAINT GREEN (-4875 4050);
DISPLAY INVISIBLE (-4875 4050);
FORCEPROP 1 LAST PATH I266
J 0
(-4875 4050);
DISPLAY 0.723404 (-4875 4050);
PAINT GREEN (-4875 4050);
DISPLAY INVISIBLE (-4875 4050);
FORCEPROP 1 LAST PART_NUMBER ALLV4052K19
J 0
(-5044 4559);
DISPLAY 0.723404 (-5044 4559);
PAINT GREEN (-5044 4559);
DISPLAY INVISIBLE (-5044 4559);
FORCEADD UNIVERSAL_GND..1
(-4475 3525);
FORCEPROP 3 LASTPIN (-4475 3575) SIG_NAME GND\g
J 0
(-4465 3585);
DISPLAY 0.659574 (-4465 3585);
PAINT MONO (-4465 3585);
DISPLAY INVISIBLE (-4465 3585);
FORCEPROP 2 LAST CDS_LIB pure_quanta_power
J 0
(-4475 3525);
PAINT MONO (-4475 3525);
DISPLAY INVISIBLE (-4475 3525);
FORCEPROP 1 LAST HDL_POWER GND
J 1
(-4450 3450);
DISPLAY 0.872340 (-4450 3450);
PAINT GREEN (-4450 3450);
DISPLAY INVISIBLE (-4450 3450);
FORCEPROP 1 LAST PATH I267
J 0
(-4400 3525);
DISPLAY 0.872340 (-4400 3525);
PAINT AQUA (-4400 3525);
DISPLAY INVISIBLE (-4400 3525);
FORCEADD UNIVERSAL_POWER..1
(-5350 4875);
FORCEPROP 3 LASTPIN (-5350 4825) SIG_NAME P3V3_AUX\g
J 0
(-5340 4835);
DISPLAY 0.659574 (-5340 4835);
PAINT MONO (-5340 4835);
DISPLAY INVISIBLE (-5340 4835);
FORCEPROP 1 LAST HDL_POWER P3V3_AUX
J 1
(-5350 4925);
DISPLAY 0.489362 (-5350 4925);
PAINT GREEN (-5350 4925);
FORCEPROP 2 LAST CDS_LIB pure_quanta_power
J 0
(-5350 4875);
PAINT MONO (-5350 4875);
DISPLAY INVISIBLE (-5350 4875);
FORCEPROP 1 LAST PATH I292
J 0
(-5300 4900);
DISPLAY 0.872340 (-5300 4900);
PAINT AQUA (-5300 4900);
DISPLAY INVISIBLE (-5300 4900);
FORCEADD Q_CAP..1
(-5475 4575);
FORCEPROP 1 LAST LOCATION C1554
J 0
(-5675 4675);
DISPLAY 0.489362 (-5675 4675);
PAINT SKYBLUE (-5675 4675);
FORCEPROP 2 LAST $SEC 1
J 0
(-5425 4775);
PAINT MONO (-5425 4775);
DISPLAY INVISIBLE (-5425 4775);
FORCEPROP 2 LAST CDS_SEC 1
J 0
(-5425 4775);
PAINT MONO (-5425 4775);
DISPLAY INVISIBLE (-5425 4775);
FORCEPROP 1 LASTPIN (-5475 4675) $PN 1
J 0
(-5465 4655);
DISPLAY 0.489362 (-5465 4655);
PAINT GREEN (-5465 4655);
FORCEPROP 1 LASTPIN (-5475 4475) $PN 2
J 0
(-5465 4455);
DISPLAY 0.489362 (-5465 4455);
PAINT GREEN (-5465 4455);
FORCEPROP 1 LAST PACK_TYPE C0402
J 0
(-5700 4425);
DISPLAY 0.489362 (-5700 4425);
PAINT SKYBLUE (-5700 4425);
FORCEPROP 1 LAST MATERIAL X7R
J 0
(-5650 4375);
DISPLAY 0.489362 (-5650 4375);
PAINT SKYBLUE (-5650 4375);
FORCEPROP 1 LAST TOLERANCE 10%
J 0
(-5650 4525);
DISPLAY 0.489362 (-5650 4525);
PAINT SKYBLUE (-5650 4525);
FORCEPROP 1 LAST VALUE 0.1UF
J 0
(-5700 4625);
DISPLAY 0.489362 (-5700 4625);
PAINT SKYBLUE (-5700 4625);
FORCEPROP 1 LAST VOLTAGE 16V
J 0
(-5650 4575);
DISPLAY 0.489362 (-5650 4575);
PAINT SKYBLUE (-5650 4575);
FORCEPROP 2 LAST CDS_LIB pure_quanta
J 0
(-5475 4575);
DISPLAY INVISIBLE (-5475 4575);
FORCEPROP 1 LAST PATH I293
J 0
(-5425 4725);
DISPLAY 0.978723 (-5425 4725);
PAINT WHITE (-5425 4725);
DISPLAY INVISIBLE (-5425 4725);
FORCEPROP 1 LAST PART_NUMBER CH4103K1B08
J 0
(-5825 4475);
DISPLAY 0.489362 (-5825 4475);
PAINT SKYBLUE (-5825 4475);
DISPLAY INVISIBLE (-5825 4475);
FORCEADD UNIVERSAL_GND..1
(-5475 4375);
FORCEPROP 3 LASTPIN (-5475 4425) SIG_NAME GND\g
J 0
(-5465 4435);
DISPLAY 0.659574 (-5465 4435);
PAINT MONO (-5465 4435);
DISPLAY INVISIBLE (-5465 4435);
FORCEPROP 2 LAST CDS_LIB pure_quanta_power
J 0
(-5475 4375);
PAINT MONO (-5475 4375);
DISPLAY INVISIBLE (-5475 4375);
FORCEPROP 1 LAST HDL_POWER GND
J 1
(-5450 4300);
DISPLAY 0.872340 (-5450 4300);
PAINT GREEN (-5450 4300);
DISPLAY INVISIBLE (-5450 4300);
FORCEPROP 1 LAST PATH I294
J 0
(-5400 4375);
DISPLAY 0.872340 (-5400 4375);
PAINT AQUA (-5400 4375);
DISPLAY INVISIBLE (-5400 4375);
FORCEADD UNIVERSAL_POWER..1
(-7700 4375);
FORCEPROP 3 LASTPIN (-7700 4325) SIG_NAME P3V3_AUX\g
J 0
(-7690 4335);
DISPLAY 0.659574 (-7690 4335);
PAINT MONO (-7690 4335);
DISPLAY INVISIBLE (-7690 4335);
FORCEPROP 1 LAST HDL_POWER P3V3_AUX
J 1
(-7700 4425);
DISPLAY 0.489362 (-7700 4425);
PAINT GREEN (-7700 4425);
FORCEPROP 2 LAST CDS_LIB pure_quanta_power
J 0
(-7700 4375);
DISPLAY INVISIBLE (-7700 4375);
FORCEPROP 1 LAST PATH I295
J 0
(-7650 4400);
DISPLAY 0.872340 (-7650 4400);
PAINT AQUA (-7650 4400);
DISPLAY INVISIBLE (-7650 4400);
FORCEADD OFFPAGE..4
R 2
(-5900 4275);
FORCEPROP 2 LAST $XR0 150 
J 0
(-6182 4275);
DISPLAY 0.638298 (-6182 4275);
PAINT MONO (-6182 4275);
FORCEPROP 2 LAST $XR1 171 
J 0
(-6302 4275);
DISPLAY 0.638298 (-6302 4275);
PAINT MONO (-6302 4275);
FORCEPROP 2 LAST CDS_LIB standard
J 0
(-5900 4275);
DISPLAY INVISIBLE (-5900 4275);
FORCEPROP 1 LAST OFFPAGE TRUE
J 2
(-6225 4150);
DISPLAY 0.872340 (-6225 4150);
PAINT GREEN (-6225 4150);
DISPLAY INVISIBLE (-6225 4150);
FORCEPROP 1 LAST COMMENT_BODY TRUE
J 2
(-5875 4175);
DISPLAY 0.872340 (-5875 4175);
PAINT GREEN (-5875 4175);
DISPLAY INVISIBLE (-5875 4175);
FORCEPROP 2 LAST PATH I296
J 0
(-6150 4325);
DISPLAY 1.021277 (-6150 4325);
DISPLAY INVISIBLE (-6150 4325);
FORCEADD OFFPAGE..4
R 2
(-5900 4075);
FORCEPROP 2 LAST $XR0 150 
J 0
(-6182 4075);
DISPLAY 0.638298 (-6182 4075);
PAINT MONO (-6182 4075);
FORCEPROP 2 LAST $XR1 171 
J 0
(-6302 4075);
DISPLAY 0.638298 (-6302 4075);
PAINT MONO (-6302 4075);
FORCEPROP 2 LAST CDS_LIB standard
J 0
(-5900 4075);
DISPLAY INVISIBLE (-5900 4075);
FORCEPROP 1 LAST OFFPAGE TRUE
J 2
(-6225 3950);
DISPLAY 0.872340 (-6225 3950);
PAINT GREEN (-6225 3950);
DISPLAY INVISIBLE (-6225 3950);
FORCEPROP 1 LAST COMMENT_BODY TRUE
J 2
(-5875 3975);
DISPLAY 0.872340 (-5875 3975);
PAINT GREEN (-5875 3975);
DISPLAY INVISIBLE (-5875 3975);
FORCEPROP 2 LAST PATH I297
J 0
(-6150 4125);
DISPLAY 1.021277 (-6150 4125);
DISPLAY INVISIBLE (-6150 4125);
FORCEADD UNIVERSAL_POWER..1
(-5350 2925);
FORCEPROP 3 LASTPIN (-5350 2875) SIG_NAME P3V3_AUX\g
J 0
(-5340 2885);
DISPLAY 0.659574 (-5340 2885);
PAINT MONO (-5340 2885);
DISPLAY INVISIBLE (-5340 2885);
FORCEPROP 1 LAST HDL_POWER P3V3_AUX
J 1
(-5350 2975);
DISPLAY 0.489362 (-5350 2975);
PAINT GREEN (-5350 2975);
FORCEPROP 2 LAST CDS_LIB pure_quanta_power
J 0
(-5350 2925);
DISPLAY INVISIBLE (-5350 2925);
FORCEPROP 1 LAST PATH I298
J 0
(-5300 2950);
DISPLAY 0.872340 (-5300 2950);
PAINT AQUA (-5300 2950);
DISPLAY INVISIBLE (-5300 2950);
FORCEADD Q_CAP..1
(-5475 2625);
FORCEPROP 1 LAST LOCATION C194
J 0
(-5625 2725);
DISPLAY 0.489362 (-5625 2725);
PAINT SKYBLUE (-5625 2725);
FORCEPROP 0 LAST $SEC 1
J 0
(-5625 2775);
DISPLAY 0.680851 (-5625 2775);
PAINT MONO (-5625 2775);
DISPLAY INVISIBLE (-5625 2775);
FORCEPROP 0 LAST CDS_SEC 1
J 0
(-5625 2775);
DISPLAY 1.021277 (-5625 2775);
DISPLAY INVISIBLE (-5625 2775);
FORCEPROP 1 LASTPIN (-5475 2725) $PN 1
J 0
(-5465 2705);
DISPLAY 0.489362 (-5465 2705);
PAINT MONO (-5465 2705);
FORCEPROP 1 LASTPIN (-5475 2525) $PN 2
J 0
(-5465 2505);
DISPLAY 0.489362 (-5465 2505);
PAINT MONO (-5465 2505);
FORCEPROP 1 LAST VALUE 0.1UF
J 0
(-5700 2675);
DISPLAY 0.489362 (-5700 2675);
PAINT SKYBLUE (-5700 2675);
FORCEPROP 1 LAST VOLTAGE 16V
J 0
(-5650 2625);
DISPLAY 0.489362 (-5650 2625);
PAINT SKYBLUE (-5650 2625);
FORCEPROP 1 LAST TOLERANCE 10%
J 0
(-5650 2575);
DISPLAY 0.489362 (-5650 2575);
PAINT SKYBLUE (-5650 2575);
FORCEPROP 1 LAST PACK_TYPE C0402
J 0
(-5700 2475);
DISPLAY 0.489362 (-5700 2475);
PAINT SKYBLUE (-5700 2475);
FORCEPROP 1 LAST MATERIAL X7R
J 0
(-5650 2425);
DISPLAY 0.489362 (-5650 2425);
PAINT SKYBLUE (-5650 2425);
FORCEPROP 2 LAST CDS_LIB pure_quanta
J 0
(-5475 2625);
DISPLAY INVISIBLE (-5475 2625);
FORCEPROP 1 LAST PATH I299
J 0
(-5425 2775);
DISPLAY 0.978723 (-5425 2775);
PAINT WHITE (-5425 2775);
DISPLAY INVISIBLE (-5425 2775);
FORCEPROP 1 LAST PART_NUMBER CH4103K1B08
J 0
(-5825 2525);
DISPLAY 0.489362 (-5825 2525);
PAINT SKYBLUE (-5825 2525);
DISPLAY INVISIBLE (-5825 2525);
FORCEADD UNIVERSAL_GND..1
(-5475 2425);
FORCEPROP 3 LASTPIN (-5475 2475) SIG_NAME GND\g
J 0
(-5465 2485);
DISPLAY 0.659574 (-5465 2485);
PAINT MONO (-5465 2485);
DISPLAY INVISIBLE (-5465 2485);
FORCEPROP 2 LAST CDS_LIB pure_quanta_power
J 0
(-5475 2425);
DISPLAY INVISIBLE (-5475 2425);
FORCEPROP 1 LAST HDL_POWER GND
J 1
(-5450 2350);
DISPLAY 0.872340 (-5450 2350);
PAINT GREEN (-5450 2350);
DISPLAY INVISIBLE (-5450 2350);
FORCEPROP 1 LAST PATH I300
J 0
(-5400 2425);
DISPLAY 0.872340 (-5400 2425);
PAINT AQUA (-5400 2425);
DISPLAY INVISIBLE (-5400 2425);
FORCEADD UNIVERSAL_GND..1
(-4425 1600);
FORCEPROP 3 LASTPIN (-4425 1650) SIG_NAME GND\g
J 0
(-4415 1660);
DISPLAY 0.659574 (-4415 1660);
PAINT MONO (-4415 1660);
DISPLAY INVISIBLE (-4415 1660);
FORCEPROP 2 LAST CDS_LIB pure_quanta_power
J 0
(-4425 1600);
PAINT MONO (-4425 1600);
DISPLAY INVISIBLE (-4425 1600);
FORCEPROP 1 LAST HDL_POWER GND
J 1
(-4400 1525);
DISPLAY 0.872340 (-4400 1525);
PAINT GREEN (-4400 1525);
DISPLAY INVISIBLE (-4400 1525);
FORCEPROP 1 LAST PATH I301
J 0
(-4350 1600);
DISPLAY 0.872340 (-4350 1600);
PAINT AQUA (-4350 1600);
DISPLAY INVISIBLE (-4350 1600);
FORCEADD 74LV4052PW..1
(-4825 2100);
FORCEPROP 1 LAST LOCATION U212
J 0
(-5000 2550);
DISPLAY 0.723404 (-5000 2550);
PAINT GREEN (-5000 2550);
FORCEPROP 2 LAST SEC 1
J 0
(-5000 2850);
DISPLAY 0.680851 (-5000 2850);
PAINT MONO (-5000 2850);
DISPLAY INVISIBLE (-5000 2850);
FORCEPROP 2 LASTPIN (-4500 2225) $PN 12
J 0
(-4490 2235);
DISPLAY 0.680851 (-4490 2235);
PAINT MONO (-4490 2235);
FORCEPROP 2 LASTPIN (-4500 2275) $PN 14
J 0
(-4490 2285);
DISPLAY 0.680851 (-4490 2285);
PAINT MONO (-4490 2285);
FORCEPROP 2 LASTPIN (-4500 2325) $PN 15
J 0
(-4490 2335);
DISPLAY 0.680851 (-4490 2335);
PAINT MONO (-4490 2335);
FORCEPROP 2 LASTPIN (-4500 2375) $PN 11
J 0
(-4490 2385);
DISPLAY 0.680851 (-4490 2385);
PAINT MONO (-4490 2385);
FORCEPROP 2 LASTPIN (-5150 2325) $PN 13
J 2
(-5160 2335);
DISPLAY 0.680851 (-5160 2335);
PAINT MONO (-5160 2335);
FORCEPROP 2 LASTPIN (-4500 1975) $PN 1
J 0
(-4490 1985);
DISPLAY 0.680851 (-4490 1985);
PAINT MONO (-4490 1985);
FORCEPROP 2 LASTPIN (-4500 2025) $PN 5
J 0
(-4490 2035);
DISPLAY 0.680851 (-4490 2035);
PAINT MONO (-4490 2035);
FORCEPROP 2 LASTPIN (-4500 2075) $PN 2
J 0
(-4490 2085);
DISPLAY 0.680851 (-4490 2085);
PAINT MONO (-4490 2085);
FORCEPROP 2 LASTPIN (-4500 2125) $PN 4
J 0
(-4490 2135);
DISPLAY 0.680851 (-4490 2135);
PAINT MONO (-4490 2135);
FORCEPROP 2 LASTPIN (-5150 2125) $PN 3
J 2
(-5160 2135);
DISPLAY 0.680851 (-5160 2135);
PAINT MONO (-5160 2135);
FORCEPROP 2 LASTPIN (-5150 1875) $PN 6
J 2
(-5160 1885);
DISPLAY 0.680851 (-5160 1885);
PAINT MONO (-5160 1885);
FORCEPROP 2 LASTPIN (-4500 1825) $PN 8
J 0
(-4490 1835);
DISPLAY 0.680851 (-4490 1835);
PAINT MONO (-4490 1835);
FORCEPROP 2 LASTPIN (-5150 1925) $PN 10
J 2
(-5160 1935);
DISPLAY 0.680851 (-5160 1935);
PAINT MONO (-5160 1935);
FORCEPROP 2 LASTPIN (-5150 1975) $PN 9
J 2
(-5160 1985);
DISPLAY 0.680851 (-5160 1985);
PAINT MONO (-5160 1985);
FORCEPROP 2 LASTPIN (-5150 2375) $PN 16
J 2
(-5160 2385);
DISPLAY 0.680851 (-5160 2385);
PAINT MONO (-5160 2385);
FORCEPROP 2 LASTPIN (-4500 1875) $PN 7
J 0
(-4490 1885);
DISPLAY 0.680851 (-4490 1885);
PAINT MONO (-4490 1885);
FORCEPROP 2 LAST VALUE 74LV4052PW
J 0
(-5000 2750);
DISPLAY 0.489362 (-5000 2750);
PAINT SKYBLUE (-5000 2750);
FORCEPROP 1 LAST MATERIAL IC
J 0
(-4994 2482);
DISPLAY 0.723404 (-4994 2482);
PAINT GREEN (-4994 2482);
FORCEPROP 2 LAST PART_TYPE SMLF
J 0
(-5000 2800);
DISPLAY 1.021277 (-5000 2800);
FORCEPROP 2 LAST SEC_TYPE 
J 0
(-5000 2850);
DISPLAY 0.680851 (-5000 2850);
DISPLAY INVISIBLE (-5000 2850);
FORCEPROP 2 LAST CDS_LIB pure_quanta
J 0
(-4825 2100);
DISPLAY INVISIBLE (-4825 2100);
FORCEPROP 1 LAST CDS_LMAN_SYM_OUTLINE -175,325,175,-325
J 0
(-4825 2100);
DISPLAY 0.468085 (-4825 2100);
PAINT GREEN (-4825 2100);
DISPLAY INVISIBLE (-4825 2100);
FORCEPROP 1 LAST NEEDS_NO_SIZE TRUE
J 0
(-4825 2100);
DISPLAY 0.723404 (-4825 2100);
PAINT GREEN (-4825 2100);
DISPLAY INVISIBLE (-4825 2100);
FORCEPROP 1 LAST PATH I302
J 0
(-4825 2100);
DISPLAY 0.723404 (-4825 2100);
PAINT GREEN (-4825 2100);
DISPLAY INVISIBLE (-4825 2100);
FORCEPROP 1 LAST PART_NUMBER ALLV4052K19
J 0
(-4994 2609);
DISPLAY 0.723404 (-4994 2609);
PAINT GREEN (-4994 2609);
DISPLAY INVISIBLE (-4994 2609);
FORCEADD Q_RES..2
(-7700 4150);
FORCEPROP 1 LAST LOCATION R1730
J 0
(-7625 4300);
DISPLAY 0.489362 (-7625 4300);
PAINT SKYBLUE (-7625 4300);
FORCEPROP 0 LAST $SEC 1
J 0
(-7625 4350);
PAINT MONO (-7625 4350);
DISPLAY INVISIBLE (-7625 4350);
FORCEPROP 0 LAST CDS_SEC 1
J 0
(-7625 4350);
PAINT MONO (-7625 4350);
DISPLAY INVISIBLE (-7625 4350);
FORCEPROP 1 LASTPIN (-7700 4250) $PN 1
J 0
(-7695 4212);
DISPLAY 0.489362 (-7695 4212);
PAINT GREEN (-7695 4212);
FORCEPROP 1 LASTPIN (-7700 4050) $PN 2
J 0
(-7695 4060);
DISPLAY 0.489362 (-7695 4060);
PAINT GREEN (-7695 4060);
FORCEPROP 1 LAST PACK_TYPE 0402LF
J 0
(-7625 4050);
DISPLAY 0.489362 (-7625 4050);
PAINT SKYBLUE (-7625 4050);
FORCEPROP 1 LAST MATERIAL EMPTY
J 0
(-7630 4200);
DISPLAY 0.489362 (-7630 4200);
PAINT RED (-7630 4200);
FORCEPROP 1 LAST VALUE 4.7K
J 0
(-7625 4250);
DISPLAY 0.489362 (-7625 4250);
PAINT SKYBLUE (-7625 4250);
FORCEPROP 1 LAST TOLERANCE 5%
J 0
(-7625 4150);
DISPLAY 0.489362 (-7625 4150);
PAINT SKYBLUE (-7625 4150);
FORCEPROP 1 LAST WATTAGE 1/16W
J 0
(-7625 4100);
DISPLAY 0.489362 (-7625 4100);
PAINT SKYBLUE (-7625 4100);
FORCEPROP 2 LAST CDS_LIB pure_quanta
J 0
(-7700 4150);
PAINT MONO (-7700 4150);
DISPLAY INVISIBLE (-7700 4150);
FORCEPROP 1 LAST PATH I305
J 0
(-7650 4325);
DISPLAY 0.978723 (-7650 4325);
PAINT WHITE (-7650 4325);
DISPLAY INVISIBLE (-7650 4325);
FORCEPROP 1 LAST PART_NUMBER CS24702JB10
J 0
(-7625 4000);
DISPLAY 0.489362 (-7625 4000);
PAINT SKYBLUE (-7625 4000);
DISPLAY INVISIBLE (-7625 4000);
FORCEADD Q_RES..2
(-7750 3650);
FORCEPROP 1 LAST LOCATION R1729
J 0
(-7675 3800);
DISPLAY 0.489362 (-7675 3800);
PAINT SKYBLUE (-7675 3800);
FORCEPROP 0 LAST $SEC 1
J 0
(-7675 3850);
PAINT MONO (-7675 3850);
DISPLAY INVISIBLE (-7675 3850);
FORCEPROP 0 LAST CDS_SEC 1
J 0
(-7675 3850);
PAINT MONO (-7675 3850);
DISPLAY INVISIBLE (-7675 3850);
FORCEPROP 1 LASTPIN (-7750 3750) $PN 1
J 0
(-7745 3712);
DISPLAY 0.489362 (-7745 3712);
PAINT GREEN (-7745 3712);
FORCEPROP 1 LASTPIN (-7750 3550) $PN 2
J 0
(-7745 3560);
DISPLAY 0.489362 (-7745 3560);
PAINT GREEN (-7745 3560);
FORCEPROP 1 LAST PACK_TYPE 0402LF
J 0
(-7675 3550);
DISPLAY 0.489362 (-7675 3550);
PAINT SKYBLUE (-7675 3550);
FORCEPROP 1 LAST WATTAGE 1/16W
J 0
(-7675 3600);
DISPLAY 0.489362 (-7675 3600);
PAINT SKYBLUE (-7675 3600);
FORCEPROP 1 LAST TOLERANCE 5%
J 0
(-7675 3650);
DISPLAY 0.489362 (-7675 3650);
PAINT SKYBLUE (-7675 3650);
FORCEPROP 1 LAST MATERIAL CHIP
J 0
(-7680 3700);
DISPLAY 0.489362 (-7680 3700);
PAINT SKYBLUE (-7680 3700);
FORCEPROP 1 LAST VALUE 4.7K
J 0
(-7675 3750);
DISPLAY 0.489362 (-7675 3750);
PAINT SKYBLUE (-7675 3750);
FORCEPROP 2 LAST CDS_LIB pure_quanta
J 0
(-7750 3650);
PAINT MONO (-7750 3650);
DISPLAY INVISIBLE (-7750 3650);
FORCEPROP 1 LAST PATH I306
J 0
(-7700 3825);
DISPLAY 0.978723 (-7700 3825);
PAINT WHITE (-7700 3825);
DISPLAY INVISIBLE (-7700 3825);
FORCEPROP 1 LAST PART_NUMBER CS24702JB10
J 0
(-7675 3500);
DISPLAY 0.489362 (-7675 3500);
PAINT SKYBLUE (-7675 3500);
DISPLAY INVISIBLE (-7675 3500);
FORCEADD UNIVERSAL_GND..1
(-7750 3400);
FORCEPROP 3 LASTPIN (-7750 3450) SIG_NAME GND\g
J 0
(-7740 3460);
DISPLAY 0.659574 (-7740 3460);
PAINT MONO (-7740 3460);
DISPLAY INVISIBLE (-7740 3460);
FORCEPROP 2 LAST CDS_LIB pure_quanta_power
J 0
(-7750 3400);
PAINT MONO (-7750 3400);
DISPLAY INVISIBLE (-7750 3400);
FORCEPROP 1 LAST HDL_POWER GND
J 1
(-7725 3325);
DISPLAY 0.872340 (-7725 3325);
PAINT GREEN (-7725 3325);
DISPLAY INVISIBLE (-7725 3325);
FORCEPROP 1 LAST PATH I307
J 0
(-7675 3400);
DISPLAY 0.872340 (-7675 3400);
PAINT AQUA (-7675 3400);
DISPLAY INVISIBLE (-7675 3400);
FORCEADD UNIVERSAL_POWER..1
(-7700 2375);
FORCEPROP 3 LASTPIN (-7700 2325) SIG_NAME P3V3_AUX\g
J 0
(-7690 2335);
DISPLAY 0.659574 (-7690 2335);
PAINT MONO (-7690 2335);
DISPLAY INVISIBLE (-7690 2335);
FORCEPROP 1 LAST HDL_POWER P3V3_AUX
J 1
(-7700 2425);
DISPLAY 0.489362 (-7700 2425);
PAINT GREEN (-7700 2425);
FORCEPROP 2 LAST CDS_LIB pure_quanta_power
J 0
(-7700 2375);
DISPLAY INVISIBLE (-7700 2375);
FORCEPROP 1 LAST PATH I308
J 0
(-7650 2400);
DISPLAY 0.872340 (-7650 2400);
PAINT AQUA (-7650 2400);
DISPLAY INVISIBLE (-7650 2400);
FORCEADD Q_RES..2
(-7700 2150);
FORCEPROP 1 LAST LOCATION R1659
J 0
(-7655 2275);
DISPLAY 0.489362 (-7655 2275);
PAINT SKYBLUE (-7655 2275);
FORCEPROP 0 LAST $SEC 1
J 0
(-7650 2325);
DISPLAY 0.680851 (-7650 2325);
PAINT MONO (-7650 2325);
DISPLAY INVISIBLE (-7650 2325);
FORCEPROP 0 LAST CDS_SEC 1
J 0
(-7650 2325);
DISPLAY 1.021277 (-7650 2325);
DISPLAY INVISIBLE (-7650 2325);
FORCEPROP 1 LASTPIN (-7700 2250) $PN 1
J 0
(-7695 2212);
DISPLAY 0.489362 (-7695 2212);
PAINT MONO (-7695 2212);
FORCEPROP 1 LASTPIN (-7700 2050) $PN 2
J 0
(-7695 2060);
DISPLAY 0.489362 (-7695 2060);
PAINT MONO (-7695 2060);
FORCEPROP 1 LAST VALUE 4.7K
J 0
(-7625 2250);
DISPLAY 0.489362 (-7625 2250);
PAINT SKYBLUE (-7625 2250);
FORCEPROP 1 LAST TOLERANCE 5%
J 0
(-7625 2150);
DISPLAY 0.489362 (-7625 2150);
PAINT SKYBLUE (-7625 2150);
FORCEPROP 1 LAST MATERIAL EMPTY
J 0
(-7630 2200);
DISPLAY 0.489362 (-7630 2200);
PAINT RED (-7630 2200);
FORCEPROP 1 LAST WATTAGE 1/16W
J 0
(-7625 2100);
DISPLAY 0.489362 (-7625 2100);
PAINT SKYBLUE (-7625 2100);
FORCEPROP 1 LAST PACK_TYPE 0402LF
J 0
(-7625 2050);
DISPLAY 0.489362 (-7625 2050);
PAINT SKYBLUE (-7625 2050);
FORCEPROP 2 LAST CDS_LIB pure_quanta
J 0
(-7700 2150);
DISPLAY INVISIBLE (-7700 2150);
FORCEPROP 1 LAST PATH I309
J 0
(-7650 2325);
DISPLAY 0.978723 (-7650 2325);
PAINT WHITE (-7650 2325);
DISPLAY INVISIBLE (-7650 2325);
FORCEPROP 1 LAST PART_NUMBER CS24702JB10
J 0
(-7625 2000);
DISPLAY 0.489362 (-7625 2000);
PAINT SKYBLUE (-7625 2000);
DISPLAY INVISIBLE (-7625 2000);
FORCEADD Q_RES..2
(-7750 1650);
FORCEPROP 1 LAST LOCATION R1658
J 0
(-7705 1775);
DISPLAY 0.489362 (-7705 1775);
PAINT SKYBLUE (-7705 1775);
FORCEPROP 0 LAST $SEC 1
J 0
(-7700 1825);
DISPLAY 0.680851 (-7700 1825);
PAINT MONO (-7700 1825);
DISPLAY INVISIBLE (-7700 1825);
FORCEPROP 0 LAST CDS_SEC 1
J 0
(-7700 1825);
DISPLAY 1.021277 (-7700 1825);
DISPLAY INVISIBLE (-7700 1825);
FORCEPROP 1 LASTPIN (-7750 1750) $PN 1
J 0
(-7745 1712);
DISPLAY 0.489362 (-7745 1712);
PAINT MONO (-7745 1712);
FORCEPROP 1 LASTPIN (-7750 1550) $PN 2
J 0
(-7745 1560);
DISPLAY 0.489362 (-7745 1560);
PAINT MONO (-7745 1560);
FORCEPROP 1 LAST WATTAGE 1/16W
J 0
(-7675 1600);
DISPLAY 0.489362 (-7675 1600);
PAINT SKYBLUE (-7675 1600);
FORCEPROP 1 LAST PACK_TYPE 0402LF
J 0
(-7675 1550);
DISPLAY 0.489362 (-7675 1550);
PAINT SKYBLUE (-7675 1550);
FORCEPROP 1 LAST VALUE 4.7K
J 0
(-7675 1750);
DISPLAY 0.489362 (-7675 1750);
PAINT SKYBLUE (-7675 1750);
FORCEPROP 1 LAST TOLERANCE 5%
J 0
(-7675 1650);
DISPLAY 0.489362 (-7675 1650);
PAINT SKYBLUE (-7675 1650);
FORCEPROP 1 LAST MATERIAL CHIP
J 0
(-7680 1700);
DISPLAY 0.489362 (-7680 1700);
PAINT SKYBLUE (-7680 1700);
FORCEPROP 2 LAST CDS_LIB pure_quanta
J 0
(-7750 1650);
DISPLAY INVISIBLE (-7750 1650);
FORCEPROP 1 LAST PATH I310
J 0
(-7700 1825);
DISPLAY 0.978723 (-7700 1825);
PAINT WHITE (-7700 1825);
DISPLAY INVISIBLE (-7700 1825);
FORCEPROP 1 LAST PART_NUMBER CS24702JB10
J 0
(-7675 1500);
DISPLAY 0.489362 (-7675 1500);
PAINT SKYBLUE (-7675 1500);
DISPLAY INVISIBLE (-7675 1500);
FORCEADD UNIVERSAL_GND..1
(-7750 1400);
FORCEPROP 3 LASTPIN (-7750 1450) SIG_NAME GND\g
J 0
(-7740 1460);
DISPLAY 0.659574 (-7740 1460);
PAINT MONO (-7740 1460);
DISPLAY INVISIBLE (-7740 1460);
FORCEPROP 2 LAST CDS_LIB pure_quanta_power
J 0
(-7750 1400);
DISPLAY INVISIBLE (-7750 1400);
FORCEPROP 1 LAST HDL_POWER GND
J 1
(-7725 1325);
DISPLAY 0.872340 (-7725 1325);
PAINT GREEN (-7725 1325);
DISPLAY INVISIBLE (-7725 1325);
FORCEPROP 1 LAST PATH I311
J 0
(-7675 1400);
DISPLAY 0.872340 (-7675 1400);
PAINT AQUA (-7675 1400);
DISPLAY INVISIBLE (-7675 1400);
FORCEADD OFFPAGE..1
(-8050 3925);
FORCEPROP 2 LAST $XR0 80 
J 0
(-8301 3925);
DISPLAY 0.638298 (-8301 3925);
PAINT MONO (-8301 3925);
FORCEPROP 2 LAST CDS_LIB standard
J 0
(-8050 3925);
DISPLAY INVISIBLE (-8050 3925);
FORCEPROP 1 LAST OFFPAGE TRUE
J 0
(-7725 3800);
DISPLAY 0.872340 (-7725 3800);
PAINT GREEN (-7725 3800);
DISPLAY INVISIBLE (-7725 3800);
FORCEPROP 1 LAST COMMENT_BODY TRUE
J 0
(-7925 3825);
DISPLAY 0.872340 (-7925 3825);
PAINT GREEN (-7925 3825);
DISPLAY INVISIBLE (-7925 3825);
FORCEPROP 2 LAST PATH I312
J 0
(-8000 4000);
DISPLAY 1.021277 (-8000 4000);
DISPLAY INVISIBLE (-8000 4000);
FORCEADD OFFPAGE..1
(-8050 1925);
FORCEPROP 2 LAST $XR0 80 
J 0
(-8301 1925);
DISPLAY 0.638298 (-8301 1925);
PAINT MONO (-8301 1925);
FORCEPROP 2 LAST CDS_LIB standard
J 0
(-8050 1925);
DISPLAY INVISIBLE (-8050 1925);
FORCEPROP 1 LAST OFFPAGE TRUE
J 0
(-7725 1800);
DISPLAY 0.872340 (-7725 1800);
PAINT GREEN (-7725 1800);
DISPLAY INVISIBLE (-7725 1800);
FORCEPROP 1 LAST COMMENT_BODY TRUE
J 0
(-7925 1825);
DISPLAY 0.872340 (-7925 1825);
PAINT GREEN (-7925 1825);
DISPLAY INVISIBLE (-7925 1825);
FORCEPROP 2 LAST PATH I313
J 0
(-8000 2000);
DISPLAY 1.021277 (-8000 2000);
DISPLAY INVISIBLE (-8000 2000);
FORCEADD OFFPAGE..5
(-5925 2325);
FORCEPROP 2 LAST $XR0 171 
J 0
(-6210 2325);
DISPLAY 0.638298 (-6210 2325);
PAINT MONO (-6210 2325);
FORCEPROP 2 LAST $XR1 151 
J 0
(-6330 2325);
DISPLAY 0.638298 (-6330 2325);
PAINT MONO (-6330 2325);
FORCEPROP 2 LAST CDS_LIB standard
J 2
(-5925 2325);
DISPLAY INVISIBLE (-5925 2325);
FORCEPROP 1 LAST OFFPAGE TRUE
J 0
(-5600 2200);
DISPLAY 0.872340 (-5600 2200);
PAINT GREEN (-5600 2200);
DISPLAY INVISIBLE (-5600 2200);
FORCEPROP 1 LAST COMMENT_BODY TRUE
J 0
(-5825 2250);
DISPLAY 0.872340 (-5825 2250);
PAINT GREEN (-5825 2250);
DISPLAY INVISIBLE (-5825 2250);
FORCEPROP 2 LAST PATH I314
J 0
(-6200 2375);
DISPLAY 1.021277 (-6200 2375);
DISPLAY INVISIBLE (-6200 2375);
FORCEADD OFFPAGE..4
R 2
(-5925 2125);
FORCEPROP 2 LAST $XR0 151 
J 0
(-6177 2125);
DISPLAY 0.638298 (-6177 2125);
PAINT MONO (-6177 2125);
FORCEPROP 2 LAST $XR1 171 
J 0
(-6297 2125);
DISPLAY 0.638298 (-6297 2125);
PAINT MONO (-6297 2125);
FORCEPROP 2 LAST CDS_LIB standard
J 0
(-5925 2125);
DISPLAY INVISIBLE (-5925 2125);
FORCEPROP 1 LAST OFFPAGE TRUE
J 2
(-6250 2000);
DISPLAY 0.872340 (-6250 2000);
PAINT GREEN (-6250 2000);
DISPLAY INVISIBLE (-6250 2000);
FORCEPROP 1 LAST COMMENT_BODY TRUE
J 2
(-5900 2025);
DISPLAY 0.872340 (-5900 2025);
PAINT GREEN (-5900 2025);
DISPLAY INVISIBLE (-5900 2025);
FORCEPROP 2 LAST PATH I315
J 0
(-6175 2175);
DISPLAY 1.021277 (-6175 2175);
DISPLAY INVISIBLE (-6175 2175);
FORCEADD OFFPAGE..5
R 2
(-1975 2025);
FORCEPROP 2 LAST $XR0 171 
J 0
(-1786 2025);
DISPLAY 0.638298 (-1786 2025);
PAINT MONO (-1786 2025);
FORCEPROP 2 LAST $XR1 172 
J 0
(-1666 2025);
DISPLAY 0.638298 (-1666 2025);
PAINT MONO (-1666 2025);
FORCEPROP 2 LAST CDS_LIB standard
J 0
(-1975 2025);
DISPLAY INVISIBLE (-1975 2025);
FORCEPROP 1 LAST OFFPAGE TRUE
J 2
(-2300 1900);
DISPLAY 0.872340 (-2300 1900);
PAINT GREEN (-2300 1900);
DISPLAY INVISIBLE (-2300 1900);
FORCEPROP 1 LAST COMMENT_BODY TRUE
J 2
(-2075 1950);
DISPLAY 0.872340 (-2075 1950);
PAINT GREEN (-2075 1950);
DISPLAY INVISIBLE (-2075 1950);
FORCEPROP 2 LAST PATH I327
J 0
(-1650 2075);
DISPLAY 0.680851 (-1650 2075);
DISPLAY INVISIBLE (-1650 2075);
FORCEADD OFFPAGE..5
R 2
(-1975 2075);
FORCEPROP 2 LAST $XR0 85 
J 0
(-1786 2075);
DISPLAY 0.638298 (-1786 2075);
PAINT MONO (-1786 2075);
FORCEPROP 2 LAST $XR1 80 
J 0
(-1696 2075);
DISPLAY 0.638298 (-1696 2075);
PAINT MONO (-1696 2075);
FORCEPROP 2 LAST CDS_LIB standard
J 0
(-1975 2075);
DISPLAY INVISIBLE (-1975 2075);
FORCEPROP 1 LAST OFFPAGE TRUE
J 2
(-2300 1950);
DISPLAY 0.872340 (-2300 1950);
PAINT GREEN (-2300 1950);
DISPLAY INVISIBLE (-2300 1950);
FORCEPROP 1 LAST COMMENT_BODY TRUE
J 2
(-2075 2000);
DISPLAY 0.872340 (-2075 2000);
PAINT GREEN (-2075 2000);
DISPLAY INVISIBLE (-2075 2000);
FORCEPROP 2 LAST PATH I331
J 0
(-1775 2125);
DISPLAY 0.680851 (-1775 2125);
DISPLAY INVISIBLE (-1775 2125);
FORCEADD Q_RES..1
(-3200 2075);
FORCEPROP 1 LAST LOCATION R1743
J 0
(-3650 2075);
DISPLAY 0.489362 (-3650 2075);
PAINT SKYBLUE (-3650 2075);
FORCEPROP 0 LAST $SEC 1
J 0
(-3450 2125);
PAINT MONO (-3450 2125);
DISPLAY INVISIBLE (-3450 2125);
FORCEPROP 0 LAST CDS_SEC 1
J 0
(-3450 2125);
PAINT MONO (-3450 2125);
DISPLAY INVISIBLE (-3450 2125);
FORCEPROP 1 LASTPIN (-3300 2075) $PN 1
J 0
(-3288 2087);
DISPLAY 0.489362 (-3288 2087);
PAINT GREEN (-3288 2087);
FORCEPROP 1 LASTPIN (-3100 2075) $PN 2
J 0
(-3138 2087);
DISPLAY 0.489362 (-3138 2087);
PAINT GREEN (-3138 2087);
FORCEPROP 1 LAST TOLERANCE 1%
J 0
(-3100 2050);
DISPLAY 0.489362 (-3100 2050);
PAINT SKYBLUE (-3100 2050);
FORCEPROP 1 LAST VALUE 22
J 2
(-3300 2075);
DISPLAY 0.489362 (-3300 2075);
PAINT SKYBLUE (-3300 2075);
FORCEPROP 1 LAST MATERIAL CHIP
J 0
(-3375 2050);
DISPLAY 0.489362 (-3375 2050);
PAINT SKYBLUE (-3375 2050);
FORCEPROP 1 LAST PACK_TYPE 0402LF
J 0
(-2950 1925);
DISPLAY 0.978723 (-2950 1925);
PAINT SKYBLUE (-2950 1925);
DISPLAY INVISIBLE (-2950 1925);
FORCEPROP 1 LAST WATTAGE 1/16W
J 2
(-3225 1925);
DISPLAY 0.978723 (-3225 1925);
PAINT SKYBLUE (-3225 1925);
DISPLAY INVISIBLE (-3225 1925);
FORCEPROP 2 LAST CDS_LIB pure_quanta
J 0
(-3200 2075);
PAINT MONO (-3200 2075);
DISPLAY INVISIBLE (-3200 2075);
FORCEPROP 1 LAST PATH I332
J 0
(-3250 2225);
DISPLAY 0.978723 (-3250 2225);
PAINT WHITE (-3250 2225);
DISPLAY INVISIBLE (-3250 2225);
FORCEPROP 1 LAST PART_NUMBER CS02202FB02
J 0
(-3250 2175);
DISPLAY 0.978723 (-3250 2175);
PAINT SKYBLUE (-3250 2175);
DISPLAY INVISIBLE (-3250 2175);
FORCEADD OFFPAGE..1
(-9000 5225);
FORCEPROP 2 LAST $XR0 150 
J 0
(-9252 5225);
DISPLAY 0.638298 (-9252 5225);
PAINT MONO (-9252 5225);
FORCEPROP 2 LAST CDS_LIB standard
J 0
(-9000 5225);
DISPLAY INVISIBLE (-9000 5225);
FORCEPROP 1 LAST OFFPAGE TRUE
J 0
(-8675 5100);
DISPLAY 0.872340 (-8675 5100);
PAINT GREEN (-8675 5100);
DISPLAY INVISIBLE (-8675 5100);
FORCEPROP 1 LAST COMMENT_BODY TRUE
J 0
(-8875 5125);
DISPLAY 0.872340 (-8875 5125);
PAINT GREEN (-8875 5125);
DISPLAY INVISIBLE (-8875 5125);
FORCEPROP 2 LAST PATH I336
J 0
(-8950 5300);
DISPLAY 0.680851 (-8950 5300);
DISPLAY INVISIBLE (-8950 5300);
FORCEADD UNIVERSAL_POWER..1
(-6575 5775);
FORCEPROP 3 LASTPIN (-6575 5725) SIG_NAME P3V3_AUX\g
J 0
(-6565 5735);
DISPLAY 0.659574 (-6565 5735);
PAINT MONO (-6565 5735);
DISPLAY INVISIBLE (-6565 5735);
FORCEPROP 1 LAST HDL_POWER P3V3_AUX
J 1
(-6575 5825);
DISPLAY 0.489362 (-6575 5825);
PAINT GREEN (-6575 5825);
FORCEPROP 2 LAST CDS_LIB pure_quanta_power
J 0
(-6575 5775);
DISPLAY INVISIBLE (-6575 5775);
FORCEPROP 2 LAST BOM_COST OCP3.0 
J 0
(-6575 5875);
DISPLAY 0.680851 (-6575 5875);
DISPLAY INVISIBLE (-6575 5875);
FORCEPROP 1 LAST PATH I337
J 0
(-6525 5800);
DISPLAY 0.872340 (-6525 5800);
PAINT AQUA (-6525 5800);
DISPLAY INVISIBLE (-6525 5800);
FORCEADD Q_RES..2
(-6575 5500);
FORCEPROP 1 LAST LOCATION R1343
J 0
(-6530 5625);
DISPLAY 0.489362 (-6530 5625);
PAINT SKYBLUE (-6530 5625);
FORCEPROP 0 LAST $SEC 1
J 0
(-6525 5675);
DISPLAY 0.680851 (-6525 5675);
PAINT MONO (-6525 5675);
DISPLAY INVISIBLE (-6525 5675);
FORCEPROP 0 LAST CDS_SEC 1
J 0
(-6525 5675);
DISPLAY 0.680851 (-6525 5675);
DISPLAY INVISIBLE (-6525 5675);
FORCEPROP 1 LASTPIN (-6575 5600) $PN 1
J 0
(-6570 5562);
DISPLAY 0.489362 (-6570 5562);
PAINT MONO (-6570 5562);
FORCEPROP 1 LASTPIN (-6575 5400) $PN 2
J 0
(-6570 5410);
DISPLAY 0.489362 (-6570 5410);
PAINT MONO (-6570 5410);
FORCEPROP 1 LAST WATTAGE 1/16W
J 0
(-6535 5475);
DISPLAY 0.489362 (-6535 5475);
PAINT SKYBLUE (-6535 5475);
FORCEPROP 1 LAST PACK_TYPE 0402LF
J 0
(-6535 5325);
DISPLAY 0.489362 (-6535 5325);
PAINT SKYBLUE (-6535 5325);
FORCEPROP 1 LAST VALUE 4.7K
J 0
(-6530 5575);
DISPLAY 0.489362 (-6530 5575);
PAINT SKYBLUE (-6530 5575);
FORCEPROP 1 LAST TOLERANCE 5%
J 0
(-6530 5525);
DISPLAY 0.489362 (-6530 5525);
PAINT SKYBLUE (-6530 5525);
FORCEPROP 1 LAST MATERIAL EMPTY
J 0
(-6535 5425);
DISPLAY 0.489362 (-6535 5425);
PAINT RED (-6535 5425);
FORCEPROP 2 LAST CDS_LIB pure_quanta
J 0
(-6575 5500);
DISPLAY INVISIBLE (-6575 5500);
FORCEPROP 2 LAST BOM_COST OCP3.0 
J 0
(-6525 5675);
DISPLAY 0.680851 (-6525 5675);
DISPLAY INVISIBLE (-6525 5675);
FORCEPROP 1 LAST PATH I339
J 0
(-6525 5675);
DISPLAY 0.978723 (-6525 5675);
PAINT WHITE (-6525 5675);
DISPLAY INVISIBLE (-6525 5675);
FORCEPROP 1 LAST PART_NUMBER CS24702JB10
J 0
(-6535 5375);
DISPLAY 0.489362 (-6535 5375);
PAINT SKYBLUE (-6535 5375);
DISPLAY INVISIBLE (-6535 5375);
FORCEADD SN74LVC1G07DBVR..1
(-7400 5225);
FORCEPROP 1 LAST LOCATION U99
J 0
(-7525 5480);
DISPLAY 0.489362 (-7525 5480);
PAINT SKYBLUE (-7525 5480);
FORCEPROP 0 LAST $SEC 1
J 0
(-7525 5625);
DISPLAY 0.680851 (-7525 5625);
PAINT MONO (-7525 5625);
DISPLAY INVISIBLE (-7525 5625);
FORCEPROP 0 LAST CDS_SEC 1
J 0
(-7525 5625);
DISPLAY 0.680851 (-7525 5625);
DISPLAY INVISIBLE (-7525 5625);
FORCEPROP 0 LASTPIN (-7575 5225) $PN 2
J 2
(-7585 5235);
DISPLAY 0.489362 (-7585 5235);
PAINT MONO (-7585 5235);
FORCEPROP 0 LASTPIN (-7575 5125) $PN 3
J 2
(-7585 5135);
DISPLAY 0.489362 (-7585 5135);
PAINT MONO (-7585 5135);
FORCEPROP 0 LASTPIN (-7225 5125) $PN 1
J 0
(-7215 5135);
DISPLAY 0.489362 (-7215 5135);
PAINT MONO (-7215 5135);
FORCEPROP 0 LASTPIN (-7575 5325) $PN 5
J 2
(-7585 5335);
DISPLAY 0.489362 (-7585 5335);
PAINT MONO (-7585 5335);
FORCEPROP 0 LASTPIN (-7225 5225) $PN 4
J 0
(-7215 5235);
DISPLAY 0.489362 (-7215 5235);
PAINT MONO (-7215 5235);
FORCEPROP 1 LAST MATERIAL EMPTY
J 0
(-7525 5385);
DISPLAY 0.489362 (-7525 5385);
PAINT RED (-7525 5385);
FORCEPROP 2 LAST VALUE SN74LVC1G07DBVR
J 0
(-7525 5575);
DISPLAY 0.489362 (-7525 5575);
PAINT SKYBLUE (-7525 5575);
FORCEPROP 2 LAST PACK_TYPE SMLF
J 0
(-7525 5525);
DISPLAY 0.489362 (-7525 5525);
PAINT SKYBLUE (-7525 5525);
FORCEPROP 1 LAST NEEDS_NO_SIZE TRUE
J 0
(-7400 5225);
DISPLAY 0.468085 (-7400 5225);
PAINT GREEN (-7400 5225);
DISPLAY INVISIBLE (-7400 5225);
FORCEPROP 2 LAST CDS_LIB pure_quanta
J 0
(-7400 5225);
DISPLAY INVISIBLE (-7400 5225);
FORCEPROP 1 LAST PATH I340
J 0
(-7300 5380);
DISPLAY 0.723404 (-7300 5380);
PAINT GREEN (-7300 5380);
DISPLAY INVISIBLE (-7300 5380);
FORCEPROP 1 LAST PART_NUMBER AL1G0007024
J 0
(-7525 5435);
DISPLAY 0.489362 (-7525 5435);
PAINT SKYBLUE (-7525 5435);
DISPLAY INVISIBLE (-7525 5435);
FORCEADD UNIVERSAL_POWER..1
(-8000 5850);
FORCEPROP 3 LASTPIN (-8000 5800) SIG_NAME P3V3_AUX\g
J 0
(-7990 5810);
DISPLAY 0.659574 (-7990 5810);
PAINT MONO (-7990 5810);
DISPLAY INVISIBLE (-7990 5810);
FORCEPROP 1 LAST HDL_POWER P3V3_AUX
J 1
(-8000 5900);
DISPLAY 0.489362 (-8000 5900);
PAINT GREEN (-8000 5900);
FORCEPROP 2 LAST CDS_LIB pure_quanta_power
J 0
(-8000 5850);
DISPLAY INVISIBLE (-8000 5850);
FORCEPROP 2 LAST BOM_COST OCP3.0 
J 0
(-8000 5950);
DISPLAY 0.680851 (-8000 5950);
DISPLAY INVISIBLE (-8000 5950);
FORCEPROP 1 LAST PATH I341
J 0
(-7950 5875);
DISPLAY 0.872340 (-7950 5875);
PAINT AQUA (-7950 5875);
DISPLAY INVISIBLE (-7950 5875);
FORCEADD Q_CAP..1
(-8000 5550);
FORCEPROP 1 LAST LOCATION C553
J 0
(-7950 5650);
DISPLAY 0.489362 (-7950 5650);
PAINT SKYBLUE (-7950 5650);
FORCEPROP 0 LAST $SEC 1
J 0
(-7950 5700);
DISPLAY 0.680851 (-7950 5700);
PAINT MONO (-7950 5700);
DISPLAY INVISIBLE (-7950 5700);
FORCEPROP 0 LAST CDS_SEC 1
J 0
(-7950 5700);
DISPLAY 0.680851 (-7950 5700);
DISPLAY INVISIBLE (-7950 5700);
FORCEPROP 1 LASTPIN (-8000 5650) $PN 1
J 0
(-7990 5630);
DISPLAY 0.489362 (-7990 5630);
PAINT MONO (-7990 5630);
FORCEPROP 1 LASTPIN (-8000 5450) $PN 2
J 0
(-7990 5430);
DISPLAY 0.489362 (-7990 5430);
PAINT MONO (-7990 5430);
FORCEPROP 1 LAST TOLERANCE 10%
J 0
(-7925 5525);
DISPLAY 0.489362 (-7925 5525);
PAINT SKYBLUE (-7925 5525);
FORCEPROP 1 LAST VALUE 0.1UF
J 0
(-7925 5625);
DISPLAY 0.489362 (-7925 5625);
PAINT SKYBLUE (-7925 5625);
FORCEPROP 1 LAST VOLTAGE 25V
J 0
(-7925 5575);
DISPLAY 0.489362 (-7925 5575);
PAINT SKYBLUE (-7925 5575);
FORCEPROP 1 LAST PACK_TYPE 0402
J 0
(-7925 5375);
DISPLAY 0.489362 (-7925 5375);
PAINT SKYBLUE (-7925 5375);
FORCEPROP 1 LAST MATERIAL X7R
J 0
(-7925 5475);
DISPLAY 0.489362 (-7925 5475);
PAINT SKYBLUE (-7925 5475);
FORCEPROP 2 LAST BOM_COST OCP3.0 
J 0
(-7975 5675);
DISPLAY 0.680851 (-7975 5675);
DISPLAY INVISIBLE (-7975 5675);
FORCEPROP 2 LAST CDS_LIB pure_quanta
J 0
(-8000 5550);
DISPLAY INVISIBLE (-8000 5550);
FORCEPROP 1 LAST PATH I342
J 0
(-7950 5700);
DISPLAY 0.978723 (-7950 5700);
PAINT WHITE (-7950 5700);
DISPLAY INVISIBLE (-7950 5700);
FORCEPROP 1 LAST PART_NUMBER CH4104K1B00
J 0
(-7925 5425);
DISPLAY 0.489362 (-7925 5425);
PAINT SKYBLUE (-7925 5425);
DISPLAY INVISIBLE (-7925 5425);
FORCEADD UNIVERSAL_GND..1
(-8000 5350);
FORCEPROP 3 LASTPIN (-8000 5400) SIG_NAME GND\g
J 0
(-7990 5410);
DISPLAY 0.659574 (-7990 5410);
PAINT MONO (-7990 5410);
DISPLAY INVISIBLE (-7990 5410);
FORCEPROP 2 LAST CDS_LIB pure_quanta_power
J 0
(-8000 5350);
DISPLAY INVISIBLE (-8000 5350);
FORCEPROP 2 LAST BOM_COST OCP3.0 
J 0
(-8200 5425);
DISPLAY 0.680851 (-8200 5425);
DISPLAY INVISIBLE (-8200 5425);
FORCEPROP 1 LAST HDL_POWER GND
J 1
(-7975 5275);
DISPLAY 0.872340 (-7975 5275);
PAINT GREEN (-7975 5275);
DISPLAY INVISIBLE (-7975 5275);
FORCEPROP 1 LAST PATH I343
J 0
(-7925 5350);
DISPLAY 0.872340 (-7925 5350);
PAINT AQUA (-7925 5350);
DISPLAY INVISIBLE (-7925 5350);
FORCEADD UNIVERSAL_GND..1
(-7650 4950);
FORCEPROP 3 LASTPIN (-7650 5000) SIG_NAME GND\g
J 0
(-7640 5010);
DISPLAY 0.659574 (-7640 5010);
PAINT MONO (-7640 5010);
DISPLAY INVISIBLE (-7640 5010);
FORCEPROP 2 LAST CDS_LIB pure_quanta_power
J 0
(-7650 4950);
DISPLAY INVISIBLE (-7650 4950);
FORCEPROP 1 LAST HDL_POWER GND
J 1
(-7625 4875);
DISPLAY 0.872340 (-7625 4875);
PAINT GREEN (-7625 4875);
DISPLAY INVISIBLE (-7625 4875);
FORCEPROP 1 LAST PATH I344
J 0
(-7575 4950);
DISPLAY 0.872340 (-7575 4950);
PAINT AQUA (-7575 4950);
DISPLAY INVISIBLE (-7575 4950);
FORCEADD OFFPAGE..4
(-1975 2275);
FORCEPROP 2 LAST $XR0 171 
J 0
(-1789 2275);
DISPLAY 0.638298 (-1789 2275);
PAINT MONO (-1789 2275);
FORCEPROP 2 LAST $XR1 172 
J 0
(-1669 2275);
DISPLAY 0.638298 (-1669 2275);
PAINT MONO (-1669 2275);
FORCEPROP 2 LAST CDS_LIB standard
J 0
(-1975 2275);
DISPLAY INVISIBLE (-1975 2275);
FORCEPROP 1 LAST OFFPAGE TRUE
J 0
(-1650 2150);
DISPLAY 0.872340 (-1650 2150);
PAINT GREEN (-1650 2150);
DISPLAY INVISIBLE (-1650 2150);
FORCEPROP 1 LAST COMMENT_BODY TRUE
J 0
(-2000 2175);
DISPLAY 0.872340 (-2000 2175);
PAINT GREEN (-2000 2175);
DISPLAY INVISIBLE (-2000 2175);
FORCEPROP 2 LAST PATH I347
J 0
(-1650 2325);
DISPLAY 0.680851 (-1650 2325);
DISPLAY INVISIBLE (-1650 2325);
FORCEADD Q_RES..1
(-3200 2275);
FORCEPROP 1 LAST LOCATION R1738
J 0
(-3650 2275);
DISPLAY 0.489362 (-3650 2275);
PAINT SKYBLUE (-3650 2275);
FORCEPROP 0 LAST $SEC 1
J 0
(-3450 2325);
PAINT MONO (-3450 2325);
DISPLAY INVISIBLE (-3450 2325);
FORCEPROP 0 LAST CDS_SEC 1
J 0
(-3450 2325);
PAINT MONO (-3450 2325);
DISPLAY INVISIBLE (-3450 2325);
FORCEPROP 1 LASTPIN (-3300 2275) $PN 1
J 0
(-3288 2287);
DISPLAY 0.489362 (-3288 2287);
PAINT GREEN (-3288 2287);
FORCEPROP 1 LASTPIN (-3100 2275) $PN 2
J 0
(-3138 2287);
DISPLAY 0.489362 (-3138 2287);
PAINT GREEN (-3138 2287);
FORCEPROP 1 LAST MATERIAL CHIP
J 0
(-3375 2250);
DISPLAY 0.489362 (-3375 2250);
PAINT SKYBLUE (-3375 2250);
FORCEPROP 1 LAST VALUE 0
J 2
(-3300 2275);
DISPLAY 0.489362 (-3300 2275);
PAINT SKYBLUE (-3300 2275);
FORCEPROP 1 LAST TOLERANCE 5%
J 0
(-3100 2250);
DISPLAY 0.489362 (-3100 2250);
PAINT SKYBLUE (-3100 2250);
FORCEPROP 1 LAST PACK_TYPE 0402LF
J 0
(-2950 2125);
DISPLAY 0.978723 (-2950 2125);
PAINT SKYBLUE (-2950 2125);
DISPLAY INVISIBLE (-2950 2125);
FORCEPROP 1 LAST WATTAGE 1/16W
J 2
(-3225 2125);
DISPLAY 0.978723 (-3225 2125);
PAINT SKYBLUE (-3225 2125);
DISPLAY INVISIBLE (-3225 2125);
FORCEPROP 2 LAST CDS_LIB pure_quanta
J 0
(-3200 2275);
PAINT MONO (-3200 2275);
DISPLAY INVISIBLE (-3200 2275);
FORCEPROP 1 LAST PATH I349
J 0
(-3250 2425);
DISPLAY 0.978723 (-3250 2425);
PAINT WHITE (-3250 2425);
DISPLAY INVISIBLE (-3250 2425);
FORCEPROP 1 LAST PART_NUMBER CS00002JB13
J 0
(-3250 2375);
DISPLAY 0.978723 (-3250 2375);
PAINT SKYBLUE (-3250 2375);
DISPLAY INVISIBLE (-3250 2375);
FORCEADD OFFPAGE..4
(-1975 2325);
FORCEPROP 2 LAST $XR0 80 
J 0
(-1789 2325);
DISPLAY 0.638298 (-1789 2325);
PAINT MONO (-1789 2325);
FORCEPROP 2 LAST $XR1 85 
J 0
(-1699 2325);
DISPLAY 0.638298 (-1699 2325);
PAINT MONO (-1699 2325);
FORCEPROP 2 LAST CDS_LIB standard
J 0
(-1975 2325);
DISPLAY INVISIBLE (-1975 2325);
FORCEPROP 1 LAST OFFPAGE TRUE
J 0
(-1650 2200);
DISPLAY 0.872340 (-1650 2200);
PAINT GREEN (-1650 2200);
DISPLAY INVISIBLE (-1650 2200);
FORCEPROP 1 LAST COMMENT_BODY TRUE
J 0
(-2000 2225);
DISPLAY 0.872340 (-2000 2225);
PAINT GREEN (-2000 2225);
DISPLAY INVISIBLE (-2000 2225);
FORCEPROP 2 LAST PATH I351
J 0
(-1775 2375);
DISPLAY 0.680851 (-1775 2375);
DISPLAY INVISIBLE (-1775 2375);
FORCEADD Q_RES..1
(-3200 2325);
FORCEPROP 1 LAST LOCATION R1742
J 0
(-3650 2325);
DISPLAY 0.489362 (-3650 2325);
PAINT SKYBLUE (-3650 2325);
FORCEPROP 0 LAST $SEC 1
J 0
(-3450 2375);
PAINT MONO (-3450 2375);
DISPLAY INVISIBLE (-3450 2375);
FORCEPROP 0 LAST CDS_SEC 1
J 0
(-3450 2375);
PAINT MONO (-3450 2375);
DISPLAY INVISIBLE (-3450 2375);
FORCEPROP 1 LASTPIN (-3300 2325) $PN 1
J 0
(-3288 2337);
DISPLAY 0.489362 (-3288 2337);
PAINT GREEN (-3288 2337);
FORCEPROP 1 LASTPIN (-3100 2325) $PN 2
J 0
(-3138 2337);
DISPLAY 0.489362 (-3138 2337);
PAINT GREEN (-3138 2337);
FORCEPROP 1 LAST TOLERANCE 1%
J 0
(-3100 2300);
DISPLAY 0.489362 (-3100 2300);
PAINT SKYBLUE (-3100 2300);
FORCEPROP 1 LAST VALUE 22
J 2
(-3300 2325);
DISPLAY 0.489362 (-3300 2325);
PAINT SKYBLUE (-3300 2325);
FORCEPROP 1 LAST MATERIAL CHIP
J 0
(-3375 2300);
DISPLAY 0.489362 (-3375 2300);
PAINT SKYBLUE (-3375 2300);
FORCEPROP 1 LAST PACK_TYPE 0402LF
J 0
(-2950 2175);
DISPLAY 0.978723 (-2950 2175);
PAINT SKYBLUE (-2950 2175);
DISPLAY INVISIBLE (-2950 2175);
FORCEPROP 1 LAST WATTAGE 1/16W
J 2
(-3225 2175);
DISPLAY 0.978723 (-3225 2175);
PAINT SKYBLUE (-3225 2175);
DISPLAY INVISIBLE (-3225 2175);
FORCEPROP 2 LAST CDS_LIB pure_quanta
J 0
(-3200 2325);
PAINT MONO (-3200 2325);
DISPLAY INVISIBLE (-3200 2325);
FORCEPROP 1 LAST PATH I352
J 0
(-3250 2475);
DISPLAY 0.978723 (-3250 2475);
PAINT WHITE (-3250 2475);
DISPLAY INVISIBLE (-3250 2475);
FORCEPROP 1 LAST PART_NUMBER CS02202FB02
J 0
(-3250 2425);
DISPLAY 0.978723 (-3250 2425);
PAINT SKYBLUE (-3250 2425);
DISPLAY INVISIBLE (-3250 2425);
FORCEADD OFFPAGE..5
R 2
(-1975 3975);
FORCEPROP 2 LAST $XR0 171 
J 0
(-1786 3975);
DISPLAY 0.638298 (-1786 3975);
PAINT MONO (-1786 3975);
FORCEPROP 2 LAST $XR1 172 
J 0
(-1666 3975);
DISPLAY 0.638298 (-1666 3975);
PAINT MONO (-1666 3975);
FORCEPROP 2 LAST CDS_LIB standard
J 0
(-1975 3975);
DISPLAY INVISIBLE (-1975 3975);
FORCEPROP 1 LAST OFFPAGE TRUE
J 2
(-2300 3850);
DISPLAY 0.872340 (-2300 3850);
PAINT GREEN (-2300 3850);
DISPLAY INVISIBLE (-2300 3850);
FORCEPROP 1 LAST COMMENT_BODY TRUE
J 2
(-2075 3900);
DISPLAY 0.872340 (-2075 3900);
PAINT GREEN (-2075 3900);
DISPLAY INVISIBLE (-2075 3900);
FORCEPROP 2 LAST PATH I355
J 0
(-1650 4025);
DISPLAY 0.680851 (-1650 4025);
DISPLAY INVISIBLE (-1650 4025);
FORCEADD Q_RES..1
(-3200 3975);
FORCEPROP 1 LAST LOCATION R1737
J 0
(-3650 3975);
DISPLAY 0.489362 (-3650 3975);
PAINT SKYBLUE (-3650 3975);
FORCEPROP 0 LAST $SEC 1
J 0
(-3525 4025);
DISPLAY 0.680851 (-3525 4025);
PAINT MONO (-3525 4025);
DISPLAY INVISIBLE (-3525 4025);
FORCEPROP 0 LAST CDS_SEC 1
J 0
(-3525 4025);
DISPLAY 1.021277 (-3525 4025);
DISPLAY INVISIBLE (-3525 4025);
FORCEPROP 1 LASTPIN (-3300 3975) $PN 1
J 0
(-3288 3987);
DISPLAY 0.489362 (-3288 3987);
PAINT MONO (-3288 3987);
FORCEPROP 1 LASTPIN (-3100 3975) $PN 2
J 0
(-3138 3987);
DISPLAY 0.489362 (-3138 3987);
PAINT MONO (-3138 3987);
FORCEPROP 1 LAST TOLERANCE 5%
J 0
(-3100 3950);
DISPLAY 0.489362 (-3100 3950);
PAINT SKYBLUE (-3100 3950);
FORCEPROP 1 LAST VALUE 0
J 2
(-3300 3975);
DISPLAY 0.489362 (-3300 3975);
PAINT SKYBLUE (-3300 3975);
FORCEPROP 1 LAST MATERIAL CHIP
J 0
(-3375 3950);
DISPLAY 0.489362 (-3375 3950);
PAINT SKYBLUE (-3375 3950);
FORCEPROP 2 LAST CDS_LIB pure_quanta
J 0
(-3200 3975);
DISPLAY INVISIBLE (-3200 3975);
FORCEPROP 1 LAST WATTAGE 1/16W
J 2
(-3225 3825);
DISPLAY 0.978723 (-3225 3825);
PAINT SKYBLUE (-3225 3825);
DISPLAY INVISIBLE (-3225 3825);
FORCEPROP 1 LAST PACK_TYPE 0402LF
J 0
(-2950 3825);
DISPLAY 0.978723 (-2950 3825);
PAINT SKYBLUE (-2950 3825);
DISPLAY INVISIBLE (-2950 3825);
FORCEPROP 1 LAST PATH I357
J 0
(-3250 4125);
DISPLAY 0.978723 (-3250 4125);
PAINT WHITE (-3250 4125);
DISPLAY INVISIBLE (-3250 4125);
FORCEPROP 1 LAST PART_NUMBER CS00002JB13
J 0
(-3250 4075);
DISPLAY 0.978723 (-3250 4075);
PAINT SKYBLUE (-3250 4075);
DISPLAY INVISIBLE (-3250 4075);
FORCEADD OFFPAGE..5
R 2
(-1975 4225);
FORCEPROP 2 LAST $XR0 171 
J 0
(-1786 4225);
DISPLAY 0.638298 (-1786 4225);
PAINT MONO (-1786 4225);
FORCEPROP 2 LAST $XR1 172 
J 0
(-1666 4225);
DISPLAY 0.638298 (-1666 4225);
PAINT MONO (-1666 4225);
FORCEPROP 2 LAST CDS_LIB standard
J 0
(-1975 4225);
DISPLAY INVISIBLE (-1975 4225);
FORCEPROP 1 LAST OFFPAGE TRUE
J 2
(-2300 4100);
DISPLAY 0.872340 (-2300 4100);
PAINT GREEN (-2300 4100);
DISPLAY INVISIBLE (-2300 4100);
FORCEPROP 1 LAST COMMENT_BODY TRUE
J 2
(-2075 4150);
DISPLAY 0.872340 (-2075 4150);
PAINT GREEN (-2075 4150);
DISPLAY INVISIBLE (-2075 4150);
FORCEPROP 2 LAST PATH I362
J 0
(-1650 4275);
DISPLAY 0.680851 (-1650 4275);
DISPLAY INVISIBLE (-1650 4275);
FORCEADD Q_RES..1
(-3200 4225);
FORCEPROP 1 LAST LOCATION R1736
J 0
(-3650 4225);
DISPLAY 0.489362 (-3650 4225);
PAINT SKYBLUE (-3650 4225);
FORCEPROP 0 LAST $SEC 1
J 0
(-3450 4275);
PAINT MONO (-3450 4275);
DISPLAY INVISIBLE (-3450 4275);
FORCEPROP 0 LAST CDS_SEC 1
J 0
(-3450 4275);
PAINT MONO (-3450 4275);
DISPLAY INVISIBLE (-3450 4275);
FORCEPROP 1 LASTPIN (-3300 4225) $PN 1
J 0
(-3288 4237);
DISPLAY 0.489362 (-3288 4237);
PAINT GREEN (-3288 4237);
FORCEPROP 1 LASTPIN (-3100 4225) $PN 2
J 0
(-3138 4237);
DISPLAY 0.489362 (-3138 4237);
PAINT GREEN (-3138 4237);
FORCEPROP 1 LAST TOLERANCE 5%
J 0
(-3100 4200);
DISPLAY 0.489362 (-3100 4200);
PAINT SKYBLUE (-3100 4200);
FORCEPROP 1 LAST VALUE 0
J 2
(-3300 4225);
DISPLAY 0.489362 (-3300 4225);
PAINT SKYBLUE (-3300 4225);
FORCEPROP 1 LAST MATERIAL CHIP
J 0
(-3375 4200);
DISPLAY 0.489362 (-3375 4200);
PAINT SKYBLUE (-3375 4200);
FORCEPROP 2 LAST CDS_LIB pure_quanta
J 0
(-3200 4225);
PAINT MONO (-3200 4225);
DISPLAY INVISIBLE (-3200 4225);
FORCEPROP 1 LAST WATTAGE 1/16W
J 2
(-3225 4075);
DISPLAY 0.978723 (-3225 4075);
PAINT SKYBLUE (-3225 4075);
DISPLAY INVISIBLE (-3225 4075);
FORCEPROP 1 LAST PACK_TYPE 0402LF
J 0
(-2950 4075);
DISPLAY 0.978723 (-2950 4075);
PAINT SKYBLUE (-2950 4075);
DISPLAY INVISIBLE (-2950 4075);
FORCEPROP 1 LAST PATH I363
J 0
(-3250 4375);
DISPLAY 0.978723 (-3250 4375);
PAINT WHITE (-3250 4375);
DISPLAY INVISIBLE (-3250 4375);
FORCEPROP 1 LAST PART_NUMBER CS00002JB13
J 0
(-3250 4325);
DISPLAY 0.978723 (-3250 4325);
PAINT SKYBLUE (-3250 4325);
DISPLAY INVISIBLE (-3250 4325);
FORCEADD OFFPAGE..5
R 2
(-1975 4025);
FORCEPROP 2 LAST $XR0 85 
J 0
(-1786 4025);
DISPLAY 0.638298 (-1786 4025);
PAINT MONO (-1786 4025);
FORCEPROP 2 LAST $XR1 80 
J 0
(-1696 4025);
DISPLAY 0.638298 (-1696 4025);
PAINT MONO (-1696 4025);
FORCEPROP 2 LAST CDS_LIB standard
J 0
(-1975 4025);
DISPLAY INVISIBLE (-1975 4025);
FORCEPROP 1 LAST OFFPAGE TRUE
J 2
(-2300 3900);
DISPLAY 0.872340 (-2300 3900);
PAINT GREEN (-2300 3900);
DISPLAY INVISIBLE (-2300 3900);
FORCEPROP 1 LAST COMMENT_BODY TRUE
J 2
(-2075 3950);
DISPLAY 0.872340 (-2075 3950);
PAINT GREEN (-2075 3950);
DISPLAY INVISIBLE (-2075 3950);
FORCEPROP 2 LAST PATH I365
J 0
(-1775 4075);
DISPLAY 0.680851 (-1775 4075);
DISPLAY INVISIBLE (-1775 4075);
FORCEADD Q_RES..1
(-3200 4025);
FORCEPROP 1 LAST LOCATION R1741
J 0
(-3650 4025);
DISPLAY 0.489362 (-3650 4025);
PAINT SKYBLUE (-3650 4025);
FORCEPROP 0 LAST $SEC 1
J 0
(-3525 4075);
DISPLAY 0.680851 (-3525 4075);
PAINT MONO (-3525 4075);
DISPLAY INVISIBLE (-3525 4075);
FORCEPROP 0 LAST CDS_SEC 1
J 0
(-3525 4075);
DISPLAY 1.021277 (-3525 4075);
DISPLAY INVISIBLE (-3525 4075);
FORCEPROP 1 LASTPIN (-3300 4025) $PN 1
J 0
(-3288 4037);
DISPLAY 0.489362 (-3288 4037);
PAINT MONO (-3288 4037);
FORCEPROP 1 LASTPIN (-3100 4025) $PN 2
J 0
(-3138 4037);
DISPLAY 0.489362 (-3138 4037);
PAINT MONO (-3138 4037);
FORCEPROP 1 LAST MATERIAL CHIP
J 0
(-3375 4000);
DISPLAY 0.489362 (-3375 4000);
PAINT SKYBLUE (-3375 4000);
FORCEPROP 1 LAST VALUE 22
J 2
(-3300 4025);
DISPLAY 0.489362 (-3300 4025);
PAINT SKYBLUE (-3300 4025);
FORCEPROP 1 LAST TOLERANCE 1%
J 0
(-3100 4000);
DISPLAY 0.489362 (-3100 4000);
PAINT SKYBLUE (-3100 4000);
FORCEPROP 1 LAST PACK_TYPE 0402LF
J 0
(-2950 3875);
DISPLAY 0.978723 (-2950 3875);
PAINT SKYBLUE (-2950 3875);
DISPLAY INVISIBLE (-2950 3875);
FORCEPROP 1 LAST WATTAGE 1/16W
J 2
(-3225 3875);
DISPLAY 0.978723 (-3225 3875);
PAINT SKYBLUE (-3225 3875);
DISPLAY INVISIBLE (-3225 3875);
FORCEPROP 2 LAST CDS_LIB pure_quanta
J 0
(-3200 4025);
DISPLAY INVISIBLE (-3200 4025);
FORCEPROP 1 LAST PATH I366
J 0
(-3250 4175);
DISPLAY 0.978723 (-3250 4175);
PAINT WHITE (-3250 4175);
DISPLAY INVISIBLE (-3250 4175);
FORCEPROP 1 LAST PART_NUMBER CS02202FB02
J 0
(-3250 4125);
DISPLAY 0.978723 (-3250 4125);
PAINT SKYBLUE (-3250 4125);
DISPLAY INVISIBLE (-3250 4125);
FORCEADD OFFPAGE..5
R 2
(-1975 4275);
FORCEPROP 2 LAST $XR0 85 
J 0
(-1786 4275);
DISPLAY 0.638298 (-1786 4275);
PAINT MONO (-1786 4275);
FORCEPROP 2 LAST $XR1 80 
J 0
(-1696 4275);
DISPLAY 0.638298 (-1696 4275);
PAINT MONO (-1696 4275);
FORCEPROP 2 LAST CDS_LIB standard
J 0
(-1975 4275);
DISPLAY INVISIBLE (-1975 4275);
FORCEPROP 1 LAST OFFPAGE TRUE
J 2
(-2300 4150);
DISPLAY 0.872340 (-2300 4150);
PAINT GREEN (-2300 4150);
DISPLAY INVISIBLE (-2300 4150);
FORCEPROP 1 LAST COMMENT_BODY TRUE
J 2
(-2075 4200);
DISPLAY 0.872340 (-2075 4200);
PAINT GREEN (-2075 4200);
DISPLAY INVISIBLE (-2075 4200);
FORCEPROP 2 LAST PATH I367
J 0
(-1775 4325);
DISPLAY 0.680851 (-1775 4325);
DISPLAY INVISIBLE (-1775 4325);
FORCEADD Q_RES..1
(-3200 4275);
FORCEPROP 1 LAST LOCATION R1740
J 0
(-3650 4275);
DISPLAY 0.489362 (-3650 4275);
PAINT SKYBLUE (-3650 4275);
FORCEPROP 0 LAST $SEC 1
J 0
(-3450 4325);
PAINT MONO (-3450 4325);
DISPLAY INVISIBLE (-3450 4325);
FORCEPROP 0 LAST CDS_SEC 1
J 0
(-3450 4325);
PAINT MONO (-3450 4325);
DISPLAY INVISIBLE (-3450 4325);
FORCEPROP 1 LASTPIN (-3300 4275) $PN 1
J 0
(-3288 4287);
DISPLAY 0.489362 (-3288 4287);
PAINT GREEN (-3288 4287);
FORCEPROP 1 LASTPIN (-3100 4275) $PN 2
J 0
(-3138 4287);
DISPLAY 0.489362 (-3138 4287);
PAINT GREEN (-3138 4287);
FORCEPROP 1 LAST MATERIAL CHIP
J 0
(-3375 4250);
DISPLAY 0.489362 (-3375 4250);
PAINT SKYBLUE (-3375 4250);
FORCEPROP 1 LAST VALUE 22
J 2
(-3300 4275);
DISPLAY 0.489362 (-3300 4275);
PAINT SKYBLUE (-3300 4275);
FORCEPROP 1 LAST TOLERANCE 1%
J 0
(-3100 4250);
DISPLAY 0.489362 (-3100 4250);
PAINT SKYBLUE (-3100 4250);
FORCEPROP 1 LAST PACK_TYPE 0402LF
J 0
(-2950 4125);
DISPLAY 0.978723 (-2950 4125);
PAINT SKYBLUE (-2950 4125);
DISPLAY INVISIBLE (-2950 4125);
FORCEPROP 1 LAST WATTAGE 1/16W
J 2
(-3225 4125);
DISPLAY 0.978723 (-3225 4125);
PAINT SKYBLUE (-3225 4125);
DISPLAY INVISIBLE (-3225 4125);
FORCEPROP 2 LAST CDS_LIB pure_quanta
J 0
(-3200 4275);
PAINT MONO (-3200 4275);
DISPLAY INVISIBLE (-3200 4275);
FORCEPROP 1 LAST PATH I368
J 0
(-3250 4425);
DISPLAY 0.978723 (-3250 4425);
PAINT WHITE (-3250 4425);
DISPLAY INVISIBLE (-3250 4425);
FORCEPROP 1 LAST PART_NUMBER CS02202FB02
J 0
(-3250 4375);
DISPLAY 0.978723 (-3250 4375);
PAINT SKYBLUE (-3250 4375);
DISPLAY INVISIBLE (-3250 4375);
FORCEADD Q_RES..2
(-8025 5025);
FORCEPROP 1 LAST LOCATION R1342
J 0
(-7980 5150);
DISPLAY 0.489362 (-7980 5150);
PAINT SKYBLUE (-7980 5150);
FORCEPROP 0 LAST $SEC 1
J 0
(-7975 5200);
DISPLAY 0.680851 (-7975 5200);
PAINT MONO (-7975 5200);
DISPLAY INVISIBLE (-7975 5200);
FORCEPROP 0 LAST CDS_SEC 1
J 0
(-7975 5200);
DISPLAY 0.680851 (-7975 5200);
DISPLAY INVISIBLE (-7975 5200);
FORCEPROP 1 LASTPIN (-8025 5125) $PN 1
J 0
(-8020 5087);
DISPLAY 0.489362 (-8020 5087);
PAINT MONO (-8020 5087);
FORCEPROP 1 LASTPIN (-8025 4925) $PN 2
J 0
(-8020 4935);
DISPLAY 0.489362 (-8020 4935);
PAINT MONO (-8020 4935);
FORCEPROP 1 LAST WATTAGE 1/16W
J 0
(-7985 5000);
DISPLAY 0.489362 (-7985 5000);
PAINT SKYBLUE (-7985 5000);
FORCEPROP 1 LAST MATERIAL CHIP
J 0
(-7985 4950);
DISPLAY 0.489362 (-7985 4950);
PAINT SKYBLUE (-7985 4950);
FORCEPROP 1 LAST TOLERANCE 1%
J 0
(-7980 5050);
DISPLAY 0.489362 (-7980 5050);
PAINT SKYBLUE (-7980 5050);
FORCEPROP 1 LAST VALUE 10K
J 0
(-7980 5100);
DISPLAY 0.489362 (-7980 5100);
PAINT SKYBLUE (-7980 5100);
FORCEPROP 1 LAST PACK_TYPE 0402LF
J 0
(-7985 4850);
DISPLAY 0.489362 (-7985 4850);
PAINT SKYBLUE (-7985 4850);
FORCEPROP 2 LAST CDS_LIB pure_quanta
J 0
(-8025 5025);
DISPLAY INVISIBLE (-8025 5025);
FORCEPROP 1 LAST PATH I369
J 0
(-7975 5200);
DISPLAY 0.978723 (-7975 5200);
PAINT WHITE (-7975 5200);
DISPLAY INVISIBLE (-7975 5200);
FORCEPROP 1 LAST PART_NUMBER CS31002FB08
J 0
(-7985 4900);
DISPLAY 0.489362 (-7985 4900);
PAINT SKYBLUE (-7985 4900);
DISPLAY INVISIBLE (-7985 4900);
FORCEADD UNIVERSAL_GND..1
(-8025 4750);
FORCEPROP 3 LASTPIN (-8025 4800) SIG_NAME GND\g
J 0
(-8015 4810);
DISPLAY 0.659574 (-8015 4810);
PAINT MONO (-8015 4810);
DISPLAY INVISIBLE (-8015 4810);
FORCEPROP 2 LAST CDS_LIB pure_quanta_power
J 0
(-8025 4750);
DISPLAY INVISIBLE (-8025 4750);
FORCEPROP 1 LAST HDL_POWER GND
J 1
(-8000 4675);
DISPLAY 0.872340 (-8000 4675);
PAINT GREEN (-8000 4675);
DISPLAY INVISIBLE (-8000 4675);
FORCEPROP 1 LAST PATH I370
J 0
(-7950 4750);
DISPLAY 0.872340 (-7950 4750);
PAINT AQUA (-7950 4750);
DISPLAY INVISIBLE (-7950 4750);
FORCEADD UNIVERSAL_GND..1
(-4225 2675);
FORCEPROP 3 LASTPIN (-4225 2725) SIG_NAME GND\g
J 0
(-4215 2735);
DISPLAY 0.659574 (-4215 2735);
PAINT MONO (-4215 2735);
DISPLAY INVISIBLE (-4215 2735);
FORCEPROP 2 LAST CDS_LIB pure_quanta_power
J 0
(-4225 2675);
DISPLAY INVISIBLE (-4225 2675);
FORCEPROP 1 LAST HDL_POWER GND
J 1
(-4200 2600);
DISPLAY 0.872340 (-4200 2600);
PAINT GREEN (-4200 2600);
DISPLAY INVISIBLE (-4200 2600);
FORCEPROP 1 LAST PATH I372
J 0
(-4150 2675);
DISPLAY 0.872340 (-4150 2675);
PAINT AQUA (-4150 2675);
DISPLAY INVISIBLE (-4150 2675);
FORCEADD Q_RES..1
(-6125 3875);
FORCEPROP 1 LAST LOCATION R6101
J 0
(-6000 3875);
DISPLAY 0.489362 (-6000 3875);
PAINT SKYBLUE (-6000 3875);
FORCEPROP 0 LAST $SEC 1
J 0
(-6000 3925);
DISPLAY 0.680851 (-6000 3925);
PAINT MONO (-6000 3925);
DISPLAY INVISIBLE (-6000 3925);
FORCEPROP 0 LAST CDS_SEC 1
J 0
(-6000 3925);
DISPLAY 0.680851 (-6000 3925);
DISPLAY INVISIBLE (-6000 3925);
FORCEPROP 1 LASTPIN (-6225 3875) $PN 1
J 0
(-6213 3887);
DISPLAY 0.489362 (-6213 3887);
PAINT MONO (-6213 3887);
FORCEPROP 1 LASTPIN (-6025 3875) $PN 2
J 0
(-6063 3887);
DISPLAY 0.489362 (-6063 3887);
PAINT MONO (-6063 3887);
FORCEPROP 1 LAST VALUE 0
J 2
(-6250 3875);
DISPLAY 0.489362 (-6250 3875);
PAINT SKYBLUE (-6250 3875);
FORCEPROP 2 LAST CDS_LIB pure_quanta
J 0
(-6125 3875);
DISPLAY INVISIBLE (-6125 3875);
FORCEPROP 2 LAST BOM_COST MEM
J 2
(-6100 4025);
DISPLAY 0.744681 (-6100 4025);
PAINT WHITE (-6100 4025);
DISPLAY INVISIBLE (-6100 4025);
FORCEPROP 1 LAST WATTAGE 1/16W
J 2
(-6200 3800);
DISPLAY 0.489362 (-6200 3800);
PAINT SKYBLUE (-6200 3800);
DISPLAY INVISIBLE (-6200 3800);
FORCEPROP 1 LAST MATERIAL CHIP
J 2
(-5950 3850);
DISPLAY 0.489362 (-5950 3850);
PAINT SKYBLUE (-5950 3850);
DISPLAY INVISIBLE (-5950 3850);
FORCEPROP 1 LAST PACK_TYPE 0402LF
J 2
(-5950 3800);
DISPLAY 0.489362 (-5950 3800);
PAINT SKYBLUE (-5950 3800);
DISPLAY INVISIBLE (-5950 3800);
FORCEPROP 1 LAST TOLERANCE 5%
J 0
(-6250 3850);
DISPLAY 0.489362 (-6250 3850);
PAINT SKYBLUE (-6250 3850);
DISPLAY INVISIBLE (-6250 3850);
FORCEPROP 1 LAST PATH I375
J 0
(-6175 4025);
DISPLAY 0.978723 (-6175 4025);
PAINT WHITE (-6175 4025);
DISPLAY INVISIBLE (-6175 4025);
FORCEPROP 1 LAST PART_NUMBER CS00002JB13
J 2
(-6000 3800);
DISPLAY 0.489362 (-6000 3800);
PAINT SKYBLUE (-6000 3800);
DISPLAY INVISIBLE (-6000 3800);
FORCEADD Q_RES..1
(-6175 1925);
FORCEPROP 1 LAST LOCATION R6102
J 0
(-6050 1925);
DISPLAY 0.489362 (-6050 1925);
PAINT SKYBLUE (-6050 1925);
FORCEPROP 0 LAST $SEC 1
J 0
(-6050 1975);
DISPLAY 0.680851 (-6050 1975);
PAINT MONO (-6050 1975);
DISPLAY INVISIBLE (-6050 1975);
FORCEPROP 0 LAST CDS_SEC 1
J 0
(-6050 1975);
DISPLAY 0.680851 (-6050 1975);
DISPLAY INVISIBLE (-6050 1975);
FORCEPROP 1 LASTPIN (-6275 1925) $PN 1
J 0
(-6263 1937);
DISPLAY 0.489362 (-6263 1937);
PAINT MONO (-6263 1937);
FORCEPROP 1 LASTPIN (-6075 1925) $PN 2
J 0
(-6113 1937);
DISPLAY 0.489362 (-6113 1937);
PAINT MONO (-6113 1937);
FORCEPROP 1 LAST VALUE 0
J 2
(-6300 1925);
DISPLAY 0.489362 (-6300 1925);
PAINT SKYBLUE (-6300 1925);
FORCEPROP 1 LAST PACK_TYPE 0402LF
J 2
(-6000 1850);
DISPLAY 0.489362 (-6000 1850);
PAINT SKYBLUE (-6000 1850);
DISPLAY INVISIBLE (-6000 1850);
FORCEPROP 1 LAST TOLERANCE 5%
J 0
(-6300 1900);
DISPLAY 0.489362 (-6300 1900);
PAINT SKYBLUE (-6300 1900);
DISPLAY INVISIBLE (-6300 1900);
FORCEPROP 1 LAST MATERIAL CHIP
J 2
(-6000 1900);
DISPLAY 0.489362 (-6000 1900);
PAINT SKYBLUE (-6000 1900);
DISPLAY INVISIBLE (-6000 1900);
FORCEPROP 1 LAST WATTAGE 1/16W
J 2
(-6250 1850);
DISPLAY 0.489362 (-6250 1850);
PAINT SKYBLUE (-6250 1850);
DISPLAY INVISIBLE (-6250 1850);
FORCEPROP 2 LAST BOM_COST MEM
J 2
(-6150 2075);
DISPLAY 0.744681 (-6150 2075);
PAINT WHITE (-6150 2075);
DISPLAY INVISIBLE (-6150 2075);
FORCEPROP 2 LAST CDS_LIB pure_quanta
J 0
(-6175 1925);
DISPLAY INVISIBLE (-6175 1925);
FORCEPROP 1 LAST PATH I376
J 0
(-6225 2075);
DISPLAY 0.978723 (-6225 2075);
PAINT WHITE (-6225 2075);
DISPLAY INVISIBLE (-6225 2075);
FORCEPROP 1 LAST PART_NUMBER CS00002JB13
J 2
(-6050 1850);
DISPLAY 0.489362 (-6050 1850);
PAINT SKYBLUE (-6050 1850);
DISPLAY INVISIBLE (-6050 1850);
FORCEADD Q_RES..2
(-5400 1000);
FORCEPROP 1 LAST LOCATION R1318
J 0
(-5355 1125);
DISPLAY 0.489362 (-5355 1125);
PAINT SKYBLUE (-5355 1125);
FORCEPROP 0 LAST $SEC 1
J 0
(-5350 1150);
DISPLAY 0.680851 (-5350 1150);
PAINT MONO (-5350 1150);
DISPLAY INVISIBLE (-5350 1150);
FORCEPROP 0 LAST CDS_SEC 1
J 0
(-5350 1150);
DISPLAY 0.680851 (-5350 1150);
DISPLAY INVISIBLE (-5350 1150);
FORCEPROP 1 LASTPIN (-5400 1100) $PN 1
J 0
(-5395 1062);
DISPLAY 0.489362 (-5395 1062);
PAINT MONO (-5395 1062);
FORCEPROP 1 LASTPIN (-5400 900) $PN 2
J 0
(-5395 910);
DISPLAY 0.489362 (-5395 910);
PAINT MONO (-5395 910);
FORCEPROP 1 LAST WATTAGE 1/16W
J 0
(-5325 950);
DISPLAY 0.489362 (-5325 950);
PAINT SKYBLUE (-5325 950);
FORCEPROP 1 LAST VALUE 4.7K
J 0
(-5325 1100);
DISPLAY 0.489362 (-5325 1100);
PAINT SKYBLUE (-5325 1100);
FORCEPROP 1 LAST MATERIAL CHIP
J 0
(-5330 1050);
DISPLAY 0.489362 (-5330 1050);
PAINT SKYBLUE (-5330 1050);
FORCEPROP 1 LAST PACK_TYPE 0402LF
J 0
(-5325 900);
DISPLAY 0.489362 (-5325 900);
PAINT SKYBLUE (-5325 900);
FORCEPROP 1 LAST TOLERANCE 5%
J 0
(-5325 1000);
DISPLAY 0.489362 (-5325 1000);
PAINT SKYBLUE (-5325 1000);
FORCEPROP 2 LAST CDS_LIB pure_quanta
J 0
(-5400 1000);
DISPLAY INVISIBLE (-5400 1000);
FORCEPROP 1 LAST PATH I378
J 0
(-5350 1175);
DISPLAY 0.978723 (-5350 1175);
PAINT WHITE (-5350 1175);
DISPLAY INVISIBLE (-5350 1175);
FORCEPROP 1 LAST PART_NUMBER CS24702JB10
J 0
(-5325 850);
DISPLAY 0.489362 (-5325 850);
PAINT SKYBLUE (-5325 850);
DISPLAY INVISIBLE (-5325 850);
FORCEADD UNIVERSAL_GND..1
(-5400 700);
FORCEPROP 3 LASTPIN (-5400 750) SIG_NAME GND\g
J 0
(-5390 760);
DISPLAY 0.659574 (-5390 760);
PAINT MONO (-5390 760);
DISPLAY INVISIBLE (-5390 760);
FORCEPROP 2 LAST CDS_LIB pure_quanta_power
J 0
(-5400 700);
DISPLAY INVISIBLE (-5400 700);
FORCEPROP 1 LAST HDL_POWER GND
J 1
(-5375 625);
DISPLAY 0.872340 (-5375 625);
PAINT GREEN (-5375 625);
DISPLAY INVISIBLE (-5375 625);
FORCEPROP 1 LAST PATH I379
J 0
(-5325 700);
DISPLAY 0.872340 (-5325 700);
PAINT AQUA (-5325 700);
DISPLAY INVISIBLE (-5325 700);
FORCEADD UNIVERSAL_POWER..1
(-5400 1750);
FORCEPROP 3 LASTPIN (-5400 1700) SIG_NAME P3V3_AUX\g
J 0
(-5390 1710);
DISPLAY 0.659574 (-5390 1710);
PAINT MONO (-5390 1710);
DISPLAY INVISIBLE (-5390 1710);
FORCEPROP 1 LAST HDL_POWER P3V3_AUX
J 1
(-5400 1800);
DISPLAY 0.489362 (-5400 1800);
PAINT GREEN (-5400 1800);
FORCEPROP 2 LAST CDS_LIB pure_quanta_power
J 0
(-5400 1750);
DISPLAY INVISIBLE (-5400 1750);
FORCEPROP 1 LAST PATH I380
J 0
(-5350 1775);
DISPLAY 0.872340 (-5350 1775);
PAINT AQUA (-5350 1775);
DISPLAY INVISIBLE (-5350 1775);
FORCEADD Q_RES..2
(-5400 1550);
FORCEPROP 1 LAST LOCATION R6181
J 0
(-5355 1675);
DISPLAY 0.489362 (-5355 1675);
PAINT SKYBLUE (-5355 1675);
FORCEPROP 0 LAST $SEC 1
J 0
(-5350 1700);
DISPLAY 0.680851 (-5350 1700);
PAINT MONO (-5350 1700);
DISPLAY INVISIBLE (-5350 1700);
FORCEPROP 0 LAST CDS_SEC 1
J 0
(-5350 1700);
DISPLAY 0.680851 (-5350 1700);
DISPLAY INVISIBLE (-5350 1700);
FORCEPROP 1 LASTPIN (-5400 1650) $PN 1
J 0
(-5395 1612);
DISPLAY 0.787234 (-5395 1612);
PAINT MONO (-5395 1612);
FORCEPROP 1 LASTPIN (-5400 1450) $PN 2
J 0
(-5395 1460);
DISPLAY 0.787234 (-5395 1460);
PAINT MONO (-5395 1460);
FORCEPROP 1 LAST WATTAGE 1/16W
J 0
(-5325 1500);
DISPLAY 0.489362 (-5325 1500);
PAINT SKYBLUE (-5325 1500);
FORCEPROP 1 LAST TOLERANCE 5%
J 0
(-5325 1550);
DISPLAY 0.489362 (-5325 1550);
PAINT SKYBLUE (-5325 1550);
FORCEPROP 1 LAST PACK_TYPE 0402LF
J 0
(-5325 1450);
DISPLAY 0.489362 (-5325 1450);
PAINT SKYBLUE (-5325 1450);
FORCEPROP 1 LAST VALUE 4.7K
J 0
(-5325 1650);
DISPLAY 0.489362 (-5325 1650);
PAINT SKYBLUE (-5325 1650);
FORCEPROP 1 LAST MATERIAL CHIP
J 0
(-5330 1600);
DISPLAY 0.489362 (-5330 1600);
PAINT SKYBLUE (-5330 1600);
FORCEPROP 2 LAST CDS_LIB pure_quanta
J 0
(-5400 1550);
DISPLAY INVISIBLE (-5400 1550);
FORCEPROP 1 LAST PATH I381
J 0
(-5350 1725);
DISPLAY 0.978723 (-5350 1725);
PAINT WHITE (-5350 1725);
DISPLAY INVISIBLE (-5350 1725);
FORCEPROP 1 LAST PART_NUMBER CS24702JB10
J 0
(-5325 1400);
DISPLAY 0.489362 (-5325 1400);
PAINT SKYBLUE (-5325 1400);
DISPLAY INVISIBLE (-5325 1400);
FORCEADD Q_RES..2
(-4225 2900);
FORCEPROP 1 LAST LOCATION R1313
J 0
(-4180 3025);
DISPLAY 0.489362 (-4180 3025);
PAINT SKYBLUE (-4180 3025);
FORCEPROP 0 LAST $SEC 1
J 0
(-4175 3050);
DISPLAY 0.680851 (-4175 3050);
PAINT MONO (-4175 3050);
DISPLAY INVISIBLE (-4175 3050);
FORCEPROP 0 LAST CDS_SEC 1
J 0
(-4175 3050);
DISPLAY 0.680851 (-4175 3050);
DISPLAY INVISIBLE (-4175 3050);
FORCEPROP 1 LASTPIN (-4225 3000) $PN 1
J 0
(-4220 2962);
DISPLAY 0.787234 (-4220 2962);
PAINT MONO (-4220 2962);
FORCEPROP 1 LASTPIN (-4225 2800) $PN 2
J 0
(-4220 2810);
DISPLAY 0.787234 (-4220 2810);
PAINT MONO (-4220 2810);
FORCEPROP 1 LAST PACK_TYPE 0402LF
J 0
(-4150 2800);
DISPLAY 0.489362 (-4150 2800);
PAINT SKYBLUE (-4150 2800);
FORCEPROP 1 LAST WATTAGE 1/16W
J 0
(-4150 2850);
DISPLAY 0.489362 (-4150 2850);
PAINT SKYBLUE (-4150 2850);
FORCEPROP 1 LAST TOLERANCE 5%
J 0
(-4150 2900);
DISPLAY 0.489362 (-4150 2900);
PAINT SKYBLUE (-4150 2900);
FORCEPROP 1 LAST VALUE 4.7K
J 0
(-4150 2975);
DISPLAY 0.489362 (-4150 2975);
PAINT SKYBLUE (-4150 2975);
FORCEPROP 1 LAST MATERIAL CHIP
J 0
(-4155 2950);
DISPLAY 0.489362 (-4155 2950);
PAINT SKYBLUE (-4155 2950);
FORCEPROP 2 LAST CDS_LIB pure_quanta
J 0
(-4225 2900);
DISPLAY INVISIBLE (-4225 2900);
FORCEPROP 1 LAST PATH I383
J 0
(-4175 3075);
DISPLAY 0.978723 (-4175 3075);
PAINT WHITE (-4175 3075);
DISPLAY INVISIBLE (-4175 3075);
FORCEPROP 1 LAST PART_NUMBER CS24702JB10
J 0
(-4150 2750);
DISPLAY 0.489362 (-4150 2750);
PAINT SKYBLUE (-4150 2750);
DISPLAY INVISIBLE (-4150 2750);
FORCEADD Q_RES..2
(-4250 3575);
FORCEPROP 1 LAST LOCATION R6182
J 0
(-4205 3700);
DISPLAY 0.489362 (-4205 3700);
PAINT SKYBLUE (-4205 3700);
FORCEPROP 0 LAST $SEC 1
J 0
(-4200 3725);
DISPLAY 0.680851 (-4200 3725);
PAINT MONO (-4200 3725);
DISPLAY INVISIBLE (-4200 3725);
FORCEPROP 0 LAST CDS_SEC 1
J 0
(-4200 3725);
DISPLAY 0.680851 (-4200 3725);
DISPLAY INVISIBLE (-4200 3725);
FORCEPROP 1 LASTPIN (-4250 3675) $PN 1
J 0
(-4245 3637);
DISPLAY 0.787234 (-4245 3637);
PAINT MONO (-4245 3637);
FORCEPROP 1 LASTPIN (-4250 3475) $PN 2
J 0
(-4245 3485);
DISPLAY 0.787234 (-4245 3485);
PAINT MONO (-4245 3485);
FORCEPROP 1 LAST WATTAGE 1/16W
J 0
(-4175 3525);
DISPLAY 0.489362 (-4175 3525);
PAINT SKYBLUE (-4175 3525);
FORCEPROP 1 LAST PACK_TYPE 0402LF
J 0
(-4175 3475);
DISPLAY 0.489362 (-4175 3475);
PAINT SKYBLUE (-4175 3475);
FORCEPROP 1 LAST MATERIAL CHIP
J 0
(-4180 3625);
DISPLAY 0.489362 (-4180 3625);
PAINT SKYBLUE (-4180 3625);
FORCEPROP 1 LAST TOLERANCE 5%
J 0
(-4175 3575);
DISPLAY 0.489362 (-4175 3575);
PAINT SKYBLUE (-4175 3575);
FORCEPROP 1 LAST VALUE 4.7K
J 0
(-4175 3675);
DISPLAY 0.489362 (-4175 3675);
PAINT SKYBLUE (-4175 3675);
FORCEPROP 2 LAST CDS_LIB pure_quanta
J 0
(-4250 3575);
DISPLAY INVISIBLE (-4250 3575);
FORCEPROP 1 LAST PATH I384
J 0
(-4200 3750);
DISPLAY 0.978723 (-4200 3750);
PAINT WHITE (-4200 3750);
DISPLAY INVISIBLE (-4200 3750);
FORCEPROP 1 LAST PART_NUMBER CS24702JB10
J 0
(-4175 3425);
DISPLAY 0.489362 (-4175 3425);
PAINT SKYBLUE (-4175 3425);
DISPLAY INVISIBLE (-4175 3425);
FORCEADD UNIVERSAL_POWER..1
(-4250 3800);
FORCEPROP 3 LASTPIN (-4250 3750) SIG_NAME P3V3_AUX\g
J 0
(-4240 3760);
DISPLAY 0.659574 (-4240 3760);
PAINT MONO (-4240 3760);
DISPLAY INVISIBLE (-4240 3760);
FORCEPROP 1 LAST HDL_POWER P3V3_AUX
J 1
(-4250 3850);
DISPLAY 0.489362 (-4250 3850);
PAINT GREEN (-4250 3850);
FORCEPROP 2 LAST CDS_LIB pure_quanta_power
J 0
(-4250 3800);
DISPLAY INVISIBLE (-4250 3800);
FORCEPROP 1 LAST PATH I385
J 0
(-4200 3825);
DISPLAY 0.872340 (-4200 3825);
PAINT AQUA (-4200 3825);
DISPLAY INVISIBLE (-4200 3825);
FORCEADD CONN3_210HP1030BR1..1
(-4700 1200);
FORCEPROP 1 LAST LOCATION JP6000
J 0
(-4763 1429);
DISPLAY 0.723404 (-4763 1429);
PAINT GREEN (-4763 1429);
FORCEPROP 2 LAST SEC 1
J 0
(-4750 1575);
DISPLAY 0.680851 (-4750 1575);
PAINT MONO (-4750 1575);
DISPLAY INVISIBLE (-4750 1575);
FORCEPROP 2 LASTPIN (-4900 1250) $PN 1
J 2
(-4910 1260);
DISPLAY 0.680851 (-4910 1260);
PAINT MONO (-4910 1260);
FORCEPROP 2 LASTPIN (-4900 1200) $PN 2
J 2
(-4910 1210);
DISPLAY 0.680851 (-4910 1210);
PAINT MONO (-4910 1210);
FORCEPROP 2 LASTPIN (-4900 1150) $PN 3
J 2
(-4910 1160);
DISPLAY 0.680851 (-4910 1160);
PAINT MONO (-4910 1160);
FORCEPROP 2 LAST PART_TYPE THLF
J 0
(-4750 1525);
DISPLAY 0.680851 (-4750 1525);
FORCEPROP 2 LAST VALUE CONN3_210-HP1-030BR1
J 0
(-4750 1475);
DISPLAY 0.553191 (-4750 1475);
FORCEPROP 1 LAST MATERIAL IO
J 0
(-4763 1324);
DISPLAY 0.723404 (-4763 1324);
PAINT GREEN (-4763 1324);
FORCEPROP 1 LAST NEEDS_NO_SIZE TRUE
J 0
(-4700 1200);
DISPLAY 0.723404 (-4700 1200);
PAINT GREEN (-4700 1200);
DISPLAY INVISIBLE (-4700 1200);
FORCEPROP 2 LAST SEC_TYPE 
J 0
(-4750 1575);
DISPLAY 0.680851 (-4750 1575);
DISPLAY INVISIBLE (-4750 1575);
FORCEPROP 1 LAST CDS_LMAN_SYM_OUTLINE -50,100,50,-100
J 0
(-4700 1200);
DISPLAY 0.468085 (-4700 1200);
PAINT GREEN (-4700 1200);
DISPLAY INVISIBLE (-4700 1200);
FORCEPROP 2 LAST CDS_LIB pure_quanta
J 0
(-4700 1200);
DISPLAY INVISIBLE (-4700 1200);
FORCEPROP 1 LAST PATH I386
J 0
(-4700 1200);
DISPLAY 0.723404 (-4700 1200);
PAINT GREEN (-4700 1200);
DISPLAY INVISIBLE (-4700 1200);
FORCEPROP 1 LAST PART_NUMBER DFHD03MS213
J 0
(-4763 1379);
DISPLAY 0.723404 (-4763 1379);
PAINT GREEN (-4763 1379);
DISPLAY INVISIBLE (-4763 1379);
FORCEADD CONN3_210HP1030BR1..1
(-3650 3150);
FORCEPROP 1 LAST LOCATION JP6001
J 0
(-3713 3379);
DISPLAY 0.723404 (-3713 3379);
PAINT GREEN (-3713 3379);
FORCEPROP 0 LAST $SEC 1
J 0
(-3700 3525);
DISPLAY 0.680851 (-3700 3525);
PAINT MONO (-3700 3525);
DISPLAY INVISIBLE (-3700 3525);
FORCEPROP 0 LAST CDS_SEC 1
J 0
(-3700 3525);
DISPLAY 0.680851 (-3700 3525);
DISPLAY INVISIBLE (-3700 3525);
FORCEPROP 0 LASTPIN (-3850 3200) $PN 1
J 2
(-3860 3210);
DISPLAY 0.680851 (-3860 3210);
PAINT MONO (-3860 3210);
FORCEPROP 0 LASTPIN (-3850 3150) $PN 2
J 2
(-3860 3160);
DISPLAY 0.680851 (-3860 3160);
PAINT MONO (-3860 3160);
FORCEPROP 0 LASTPIN (-3850 3100) $PN 3
J 2
(-3860 3110);
DISPLAY 0.680851 (-3860 3110);
PAINT MONO (-3860 3110);
FORCEPROP 2 LAST VALUE CONN3_210-HP1-030BR1
J 0
(-3700 3425);
DISPLAY 0.553191 (-3700 3425);
FORCEPROP 1 LAST MATERIAL IO
J 0
(-3713 3274);
DISPLAY 0.723404 (-3713 3274);
PAINT GREEN (-3713 3274);
FORCEPROP 2 LAST PART_TYPE THLF
J 0
(-3700 3475);
DISPLAY 0.680851 (-3700 3475);
FORCEPROP 2 LAST CDS_LIB pure_quanta
J 0
(-3650 3150);
DISPLAY INVISIBLE (-3650 3150);
FORCEPROP 1 LAST CDS_LMAN_SYM_OUTLINE -50,100,50,-100
J 0
(-3650 3150);
DISPLAY 0.468085 (-3650 3150);
PAINT GREEN (-3650 3150);
DISPLAY INVISIBLE (-3650 3150);
FORCEPROP 1 LAST NEEDS_NO_SIZE TRUE
J 0
(-3650 3150);
DISPLAY 0.723404 (-3650 3150);
PAINT GREEN (-3650 3150);
DISPLAY INVISIBLE (-3650 3150);
FORCEPROP 1 LAST PATH I387
J 0
(-3650 3150);
DISPLAY 0.723404 (-3650 3150);
PAINT GREEN (-3650 3150);
DISPLAY INVISIBLE (-3650 3150);
FORCEPROP 1 LAST PART_NUMBER DFHD03MS213
J 0
(-3713 3329);
DISPLAY 0.723404 (-3713 3329);
PAINT GREEN (-3713 3329);
DISPLAY INVISIBLE (-3713 3329);
FORCEADD Q_RES..1
(-3200 2025);
FORCEPROP 1 LAST LOCATION R1739
J 0
(-3650 2025);
DISPLAY 0.489362 (-3650 2025);
PAINT SKYBLUE (-3650 2025);
FORCEPROP 0 LAST $SEC 1
J 0
(-3300 2050);
DISPLAY 0.680851 (-3300 2050);
PAINT MONO (-3300 2050);
DISPLAY INVISIBLE (-3300 2050);
FORCEPROP 0 LAST CDS_SEC 1
J 0
(-3300 2050);
DISPLAY 0.680851 (-3300 2050);
DISPLAY INVISIBLE (-3300 2050);
FORCEPROP 1 LASTPIN (-3300 2025) $PN 1
J 0
(-3288 2037);
DISPLAY 0.787234 (-3288 2037);
PAINT MONO (-3288 2037);
FORCEPROP 1 LASTPIN (-3100 2025) $PN 2
J 0
(-3138 2037);
DISPLAY 0.787234 (-3138 2037);
PAINT MONO (-3138 2037);
FORCEPROP 1 LAST MATERIAL CHIP
J 0
(-3375 2000);
DISPLAY 0.489362 (-3375 2000);
PAINT SKYBLUE (-3375 2000);
FORCEPROP 1 LAST VALUE 0
J 2
(-3300 2025);
DISPLAY 0.489362 (-3300 2025);
PAINT SKYBLUE (-3300 2025);
FORCEPROP 1 LAST TOLERANCE 5%
J 0
(-3100 2000);
DISPLAY 0.489362 (-3100 2000);
PAINT SKYBLUE (-3100 2000);
FORCEPROP 2 LAST CDS_LIB pure_quanta
J 0
(-3200 2025);
DISPLAY INVISIBLE (-3200 2025);
FORCEPROP 1 LAST PACK_TYPE 0402LF
J 0
(-2950 1875);
DISPLAY 0.978723 (-2950 1875);
PAINT SKYBLUE (-2950 1875);
DISPLAY INVISIBLE (-2950 1875);
FORCEPROP 1 LAST WATTAGE 1/16W
J 2
(-3225 1875);
DISPLAY 0.978723 (-3225 1875);
PAINT SKYBLUE (-3225 1875);
DISPLAY INVISIBLE (-3225 1875);
FORCEPROP 1 LAST PATH I388
J 0
(-3250 2175);
DISPLAY 0.978723 (-3250 2175);
PAINT WHITE (-3250 2175);
DISPLAY INVISIBLE (-3250 2175);
FORCEPROP 1 LAST PART_NUMBER CS00002JB13
J 0
(-3250 2125);
DISPLAY 0.978723 (-3250 2125);
PAINT SKYBLUE (-3250 2125);
DISPLAY INVISIBLE (-3250 2125);
FORCEADD CAD_NOTE..1
(-6750 1825);
FORCEPROP 0 LAST L1 R6102 PLACE CLOSE TO U212
J 0
(-6900 1700);
DISPLAY 0.617021 (-6900 1700);
PAINT WHITE (-6900 1700);
FORCEPROP 2 LAST CDS_LIB pure_quanta_power
J 0
(-6750 1825);
DISPLAY INVISIBLE (-6750 1825);
FORCEPROP 1 LAST COMMENT_BODY TRUE
J 0
(-6725 1925);
DISPLAY 0.574468 (-6725 1925);
PAINT WHITE (-6725 1925);
DISPLAY INVISIBLE (-6725 1925);
FORCEADD CAD_NOTE..1
(-6350 3725);
FORCEPROP 0 LAST L1 R6101 PLACE CLOSE TO U160
J 0
(-6500 3600);
DISPLAY 0.617021 (-6500 3600);
PAINT WHITE (-6500 3600);
FORCEPROP 2 LAST CDS_LIB pure_quanta_power
J 0
(-6350 3725);
DISPLAY INVISIBLE (-6350 3725);
FORCEPROP 1 LAST COMMENT_BODY TRUE
J 0
(-6325 3825);
DISPLAY 0.574468 (-6325 3825);
PAINT WHITE (-6325 3825);
DISPLAY INVISIBLE (-6325 3825);
FORCEADD DNS..2
(-3150 6075);
PAINT RED (-3150 6075);
FORCEPROP 2 LAST CDS_LIB mstr_misc
J 0
(-3150 6075);
DISPLAY INVISIBLE (-3150 6075);
FORCEPROP 1 LAST COMMENT_BODY TRUE
J 0
(-3150 6075);
PAINT RED (-3150 6075);
DISPLAY INVISIBLE (-3150 6075);
FORCEADD DNS..2
(-3350 6075);
PAINT RED (-3350 6075);
FORCEPROP 2 LAST CDS_LIB mstr_misc
J 0
(-3350 6075);
DISPLAY INVISIBLE (-3350 6075);
FORCEPROP 1 LAST COMMENT_BODY TRUE
J 0
(-3350 6075);
PAINT RED (-3350 6075);
DISPLAY INVISIBLE (-3350 6075);
FORCEADD DNS..2
(-3575 6075);
PAINT RED (-3575 6075);
FORCEPROP 2 LAST CDS_LIB mstr_misc
J 0
(-3575 6075);
DISPLAY INVISIBLE (-3575 6075);
FORCEPROP 1 LAST COMMENT_BODY TRUE
J 0
(-3575 6075);
PAINT RED (-3575 6075);
DISPLAY INVISIBLE (-3575 6075);
FORCEADD DNS..2
(-2875 5525);
PAINT RED (-2875 5525);
FORCEPROP 2 LAST CDS_LIB mstr_misc
J 0
(-2875 5525);
DISPLAY INVISIBLE (-2875 5525);
FORCEPROP 1 LAST COMMENT_BODY TRUE
J 0
(-2875 5525);
PAINT RED (-2875 5525);
DISPLAY INVISIBLE (-2875 5525);
FORCEADD QUANTA_TITLE_BLOCK_C..1
(0 0);
FORCEPROP 0 LAST CDS_CON_LAST_MODIFIED Thu Sep 14 16:12:15 2023
J 0
(-1885 15);
DISPLAY INVISIBLE (-1885 15);
FORCEPROP 1 LAST CUSTOM_TXT_CDS <CON_LAST_MODIFIED>
J 0
(-1885 15);
DISPLAY 0.978723 (-1885 15);
FORCEPROP 2 LAST CUSTOM_TXT_CDS <XR_PAGE_TITLE>
J 0
(-7890 5250);
DISPLAY 0.638298 (-7890 5250);
PAINT PINK (-7890 5250);
DISPLAY INVISIBLE (-7890 5250);
FORCEPROP 1 LAST CUSTOM_TXT_CDS <NAME_2>
J 0
(-3175 50);
FORCEPROP 1 LAST CUSTOM_TXT_CDS <NAME_1>
J 0
(-3175 175);
FORCEPROP 1 LAST CUSTOM_TXT_CDS <Q_NUMBER>
J 0
(-1403 103);
DISPLAY 1.212766 (-1403 103);
FORCEPROP 1 LAST CUSTOM_TXT_CDS <Q_PROJ>
J 0
(-2382 102);
DISPLAY 1.212766 (-2382 102);
FORCEPROP 1 LAST CUSTOM_TXT_CDS <Q_REV>
J 0
(-184 103);
DISPLAY 1.212766 (-184 103);
FORCEPROP 1 LAST CUSTOM_TXT_CDS <CON_PAGE_NUM> OF <CON_TOTAL_PAGES>
J 0
(-446 18);
DISPLAY 0.978723 (-446 18);
FORCEPROP 1 LAST Q_TITLE JTAG - BMC MUX
J 0
(-9275 50);
DISPLAY 2.446809 (-9275 50);
PAINT GREEN (-9275 50);
FORCEPROP 2 LAST CDS_XR_PAGE_TITLE CR-171 : @T6G_MB_LIB.T6G(SCH_1):PAGE171
J 0
(-7890 5250);
DISPLAY 0.638298 (-7890 5250);
PAINT PINK (-7890 5250);
DISPLAY INVISIBLE (-7890 5250);
FORCEPROP 1 LAST CDS_LMAN_SYM_OUTLINE -9475,6775,100,-125
J 0
(0 0);
DISPLAY 0.468085 (0 0);
PAINT GREEN (0 0);
DISPLAY INVISIBLE (0 0);
FORCEPROP 2 LAST CDS_LIB pure_quanta
J 0
(0 0);
DISPLAY INVISIBLE (0 0);
FORCEPROP 2 LAST PAGE_BORDER TRUE
J 0
(-7890 5250);
DISPLAY 0.638298 (-7890 5250);
PAINT PINK (-7890 5250);
DISPLAY INVISIBLE (-7890 5250);
FORCEPROP 1 LAST Q_DEPT BU9
J 1
(-3763 49);
DISPLAY 1.957447 (-3763 49);
PAINT GREEN (-3763 49);
DISPLAY INVISIBLE (-3763 49);
FORCEPROP 1 LAST COMMENT_BODY TRUE
J 0
(12 -13);
DISPLAY 0.978723 (12 -13);
PAINT GREEN (12 -13);
DISPLAY INVISIBLE (12 -13);
FORCEADD DNS..2
(-475 5500);
PAINT RED (-475 5500);
FORCEPROP 2 LAST CDS_LIB mstr_misc
J 0
(-475 5500);
PAINT MONO (-475 5500);
DISPLAY INVISIBLE (-475 5500);
FORCEPROP 1 LAST COMMENT_BODY TRUE
J 0
(-475 5500);
PAINT RED (-475 5500);
DISPLAY INVISIBLE (-475 5500);
FORCEADD DNS..2
(-7725 4125);
PAINT RED (-7725 4125);
FORCEPROP 2 LAST CDS_LIB mstr_misc
J 0
(-7725 4125);
PAINT MONO (-7725 4125);
DISPLAY INVISIBLE (-7725 4125);
FORCEPROP 1 LAST COMMENT_BODY TRUE
J 0
(-7725 4125);
PAINT RED (-7725 4125);
DISPLAY INVISIBLE (-7725 4125);
FORCEADD DNS..2
(-7725 2125);
PAINT RED (-7725 2125);
FORCEPROP 2 LAST CDS_LIB mstr_misc
J 0
(-7725 2125);
DISPLAY INVISIBLE (-7725 2125);
FORCEPROP 1 LAST COMMENT_BODY TRUE
J 0
(-7725 2125);
PAINT RED (-7725 2125);
DISPLAY INVISIBLE (-7725 2125);
FORCEADD DNS..2
(-7375 5175);
PAINT RED (-7375 5175);
FORCEPROP 2 LAST CDS_LIB mstr_misc
J 0
(-7375 5175);
DISPLAY INVISIBLE (-7375 5175);
FORCEPROP 1 LAST COMMENT_BODY TRUE
J 0
(-7375 5175);
PAINT RED (-7375 5175);
DISPLAY INVISIBLE (-7375 5175);
FORCEADD DNS..2
(-6575 5425);
PAINT RED (-6575 5425);
FORCEPROP 2 LAST CDS_LIB mstr_misc
J 0
(-6575 5425);
DISPLAY INVISIBLE (-6575 5425);
FORCEPROP 1 LAST COMMENT_BODY TRUE
J 0
(-6575 5425);
PAINT RED (-6575 5425);
DISPLAY INVISIBLE (-6575 5425);
WIRE 16 -1 (-2875 5450)(-2875 5375);
WIRE 16 -1 (-450 5425)(-450 5350);
WIRE 16 -1 (-5475 4475)(-5475 4425);
WIRE 16 -1 (-7700 4325)(-7700 4250);
WIRE 16 -1 (-5475 2525)(-5475 2475);
WIRE 16 -1 (-7750 3450)(-7750 3550);
WIRE 16 -1 (-7700 2325)(-7700 2250);
WIRE 16 -1 (-7750 1450)(-7750 1550);
WIRE 16 -1 (-6575 5600)(-6575 5725);
WIRE 16 -1 (-8000 5400)(-8000 5450);
WIRE 16 -1 (-7575 5125)(-7650 5125);
WIRE 16 -1 (-7650 5125)(-7650 5000);
WIRE 16 -1 (-8025 4925)(-8025 4800);
WIRE 16 -1 (-4225 2800)(-4225 2725);
WIRE 16 -1 (-5400 900)(-5400 750);
WIRE 16 -1 (-5400 1700)(-5400 1650);
WIRE 16 -1 (-4250 3675)(-4250 3750);
WIRE 16 -1 (-4550 4225)(-3300 4225);
FORCEPROP 2 LAST SIG_NAME JTAG_SCM_MUX_R_TCK
J 0
(-4400 4235);
DISPLAY 0.489362 (-4400 4235);
FORCEPROP 2 LASTPROP $XRERR UNIQUE?
J 0
(-4640 4235);
DISPLAY 0.638298 (-4640 4235);
PAINT MONO (-4640 4235);
DISPLAY INVISIBLE (-4640 4235);
WIRE 16 -1 (-4550 4175)(-3300 4175);
FORCEPROP 2 LAST SIG_NAME TP_JTAG_SCM_SLOT3_R_TCK
J 0
(-4400 4185);
DISPLAY 0.489362 (-4400 4185);
FORCEPROP 2 LASTPROP $XRERR UNIQUE?
J 0
(-3270 4175);
DISPLAY 0.638298 (-3270 4175);
PAINT MONO (-3270 4175);
DISPLAY INVISIBLE (-3270 4175);
WIRE 16 -1 (-4550 3975)(-3300 3975);
FORCEPROP 2 LAST SIG_NAME JTAG_SCM_MUX_R_TMS
J 0
(-4400 3985);
DISPLAY 0.489362 (-4400 3985);
FORCEPROP 2 LASTPROP $XRERR UNIQUE?
J 0
(-4640 3985);
DISPLAY 0.638298 (-4640 3985);
PAINT MONO (-4640 3985);
DISPLAY INVISIBLE (-4640 3985);
WIRE 16 -1 (-4500 2375)(-3725 2375);
WIRE 16 -1 (-3725 2375)(-3725 2325);
WIRE 16 -1 (-3725 2325)(-3300 2325);
WIRE 16 -1 (-4500 2325)(-3725 2325);
FORCEPROP 2 LAST SIG_NAME JTAG_SCM_PLD_R_TDI
J 0
(-4400 2335);
DISPLAY 0.489362 (-4400 2335);
FORCEPROP 2 LASTPROP $XRERR UNIQUE?
J 0
(-4640 2335);
DISPLAY 0.638298 (-4640 2335);
PAINT MONO (-4640 2335);
DISPLAY INVISIBLE (-4640 2335);
WIRE 16 -1 (-4500 2275)(-3300 2275);
FORCEPROP 2 LAST SIG_NAME JTAG_SCM_MUX_R_TDI
J 0
(-4400 2285);
DISPLAY 0.489362 (-4400 2285);
FORCEPROP 2 LASTPROP $XRERR UNIQUE?
J 0
(-4640 2285);
DISPLAY 0.638298 (-4640 2285);
PAINT MONO (-4640 2285);
DISPLAY INVISIBLE (-4640 2285);
WIRE 16 -1 (-4500 2225)(-3300 2225);
FORCEPROP 2 LAST SIG_NAME TP_JTAG_SCM_SLOT3_R_TDI
J 0
(-4400 2235);
DISPLAY 0.489362 (-4400 2235);
FORCEPROP 2 LASTPROP $XRERR UNIQUE?
J 0
(-3270 2225);
DISPLAY 0.638298 (-3270 2225);
PAINT MONO (-3270 2225);
DISPLAY INVISIBLE (-3270 2225);
WIRE 16 -1 (-4500 2125)(-3775 2125);
WIRE 16 -1 (-3775 2125)(-3775 2075);
WIRE 16 -1 (-3775 2075)(-3300 2075);
WIRE 16 -1 (-4500 2075)(-3775 2075);
FORCEPROP 2 LAST SIG_NAME JTAG_SCM_PLD_R_TDO
J 0
(-4400 2085);
DISPLAY 0.489362 (-4400 2085);
FORCEPROP 2 LASTPROP $XRERR UNIQUE?
J 0
(-4640 2085);
DISPLAY 0.638298 (-4640 2085);
PAINT MONO (-4640 2085);
DISPLAY INVISIBLE (-4640 2085);
WIRE 16 -1 (-4500 1975)(-3300 1975);
FORCEPROP 2 LAST SIG_NAME TP_JTAG_SCM_SLOT3_R_TDO
J 0
(-4400 1985);
DISPLAY 0.489362 (-4400 1985);
FORCEPROP 2 LASTPROP $XRERR UNIQUE?
J 0
(-3270 1975);
DISPLAY 0.638298 (-3270 1975);
PAINT MONO (-3270 1975);
DISPLAY INVISIBLE (-3270 1975);
WIRE 16 -1 (-5400 1450)(-5400 1250);
WIRE 16 -1 (-5400 1250)(-4900 1250);
FORCEPROP 2 LAST SIG_NAME PU_U212_EN_N
J 0
(-5335 1260);
DISPLAY 0.680851 (-5335 1260);
FORCEPROP 2 LASTPROP $XRERR UNIQUE?
J 0
(-5575 1260);
DISPLAY 0.638298 (-5575 1260);
PAINT MONO (-5575 1260);
DISPLAY INVISIBLE (-5575 1260);
WIRE 16 -1 (-5675 1875)(-5150 1875);
FORCEPROP 2 LAST SIG_NAME U212_EN_N
J 0
(-5585 1885);
DISPLAY 0.489362 (-5585 1885);
FORCEPROP 2 LASTPROP $XRERR UNIQUE?
J 0
(-5825 1885);
DISPLAY 0.638298 (-5825 1885);
PAINT MONO (-5825 1885);
DISPLAY INVISIBLE (-5825 1885);
WIRE 16 -1 (-5675 1875)(-5675 1200);
WIRE 16 -1 (-5675 1200)(-4900 1200);
WIRE 16 -1 (-3525 6250)(-3325 6250);
WIRE 16 -1 (-3525 6350)(-3525 6250);
WIRE 16 -1 (-3525 6250)(-3525 6150);
WIRE 16 -1 (-3325 6250)(-3125 6250);
WIRE 16 -1 (-3325 6150)(-3325 6250);
WIRE 16 -1 (-3125 6250)(-2875 6250);
WIRE 16 -1 (-3125 6250)(-3125 6150);
WIRE 16 -1 (-2875 6250)(-2875 6150);
WIRE 16 -1 (-1075 6225)(-875 6225);
WIRE 16 -1 (-1075 6325)(-1075 6225);
WIRE 16 -1 (-1075 6225)(-1075 6125);
WIRE 16 -1 (-875 6225)(-675 6225);
WIRE 16 -1 (-875 6125)(-875 6225);
WIRE 16 -1 (-675 6225)(-450 6225);
WIRE 16 -1 (-675 6225)(-675 6125);
WIRE 16 -1 (-450 6225)(-450 6125);
WIRE 16 -1 (-4550 3825)(-4475 3825);
WIRE 16 -1 (-4475 3825)(-4475 3775);
WIRE 16 -1 (-4475 3775)(-4550 3775);
WIRE 16 -1 (-4475 3775)(-4475 3575);
WIRE 16 -1 (-5350 4825)(-5350 4750);
WIRE 16 -1 (-5475 4750)(-5350 4750);
WIRE 16 -1 (-5350 4750)(-5350 4325);
WIRE 16 -1 (-5350 4325)(-5200 4325);
WIRE 16 -1 (-5475 4675)(-5475 4750);
WIRE 16 -1 (-5350 2875)(-5350 2800);
WIRE 16 -1 (-5475 2800)(-5350 2800);
WIRE 16 -1 (-5350 2800)(-5350 2375);
WIRE 16 -1 (-5350 2375)(-5150 2375);
WIRE 16 -1 (-5475 2725)(-5475 2800);
WIRE 16 -1 (-4500 1875)(-4425 1875);
WIRE 16 -1 (-4425 1875)(-4425 1825);
WIRE 16 -1 (-4425 1825)(-4500 1825);
WIRE 16 -1 (-4425 1825)(-4425 1650);
WIRE 16 -1 (-8000 5700)(-7650 5700);
WIRE 16 -1 (-8000 5800)(-8000 5700);
WIRE 16 -1 (-8000 5700)(-8000 5650);
WIRE 16 -1 (-7650 5700)(-7650 5325);
WIRE 16 -1 (-7650 5325)(-7575 5325);
WIRE 16 -1 (-3100 4275)(-2025 4275);
FORCEPROP 2 LAST SIG_NAME JTAG_SCM_PLD_TCK
J 0
(-2885 4285);
DISPLAY 0.489362 (-2885 4285);
WIRE 16 -1 (-1950 5825)(-1075 5825);
FORCEPROP 2 LAST SIG_NAME JTAG_SCM_MUX_TDI
J 0
(-1885 5835);
DISPLAY 0.489362 (-1885 5835);
WIRE 16 -1 (-1075 5825)(-1075 5925);
WIRE 16 -1 (-875 5925)(-875 5775);
WIRE 16 -1 (-875 5775)(-1950 5775);
FORCEPROP 2 LAST SIG_NAME JTAG_SCM_MUX_TDO
J 0
(-1885 5785);
DISPLAY 0.489362 (-1885 5785);
WIRE 16 -1 (-675 5925)(-675 5725);
WIRE 16 -1 (-675 5725)(-1950 5725);
FORCEPROP 2 LAST SIG_NAME JTAG_SCM_MUX_TMS
J 0
(-1885 5735);
DISPLAY 0.489362 (-1885 5735);
WIRE 16 -1 (-4250 3475)(-4250 3200);
FORCEPROP 2 LAST SIG_NAME PU_U160_EN_N
J 0
(-4235 3235);
DISPLAY 0.680851 (-4235 3235);
FORCEPROP 2 LASTPROP $XRERR UNIQUE?
J 0
(-4475 3235);
DISPLAY 0.638298 (-4475 3235);
PAINT MONO (-4475 3235);
DISPLAY INVISIBLE (-4475 3235);
WIRE 16 -1 (-4250 3200)(-3850 3200);
WIRE 16 -1 (-5725 3825)(-5200 3825);
FORCEPROP 2 LAST SIG_NAME U160_EN_N
J 0
(-5635 3835);
DISPLAY 0.489362 (-5635 3835);
FORCEPROP 2 LASTPROP $XRERR UNIQUE?
J 0
(-5875 3835);
DISPLAY 0.638298 (-5875 3835);
PAINT MONO (-5875 3835);
DISPLAY INVISIBLE (-5875 3835);
WIRE 16 -1 (-5725 3825)(-5725 3150);
WIRE 16 -1 (-5725 3150)(-3850 3150);
WIRE 16 -1 (-5875 2125)(-5150 2125);
FORCEPROP 2 LAST SIG_NAME JTAG_SCM_TDO
J 0
(-5785 2135);
DISPLAY 0.489362 (-5785 2135);
WIRE 16 -1 (-7225 5225)(-6575 5225);
WIRE 16 -1 (-6575 5225)(-6575 5400);
WIRE 16 -1 (-6575 5225)(-6575 3925);
WIRE 16 -1 (-6575 3925)(-5200 3925);
WIRE 16 -1 (-7700 3925)(-6575 3925);
FORCEPROP 2 LAST SIG_NAME SCM_JTAG_MUX_S1
J 0
(-7160 3935);
DISPLAY 0.489362 (-7160 3935);
WIRE 16 -1 (-6575 1975)(-6575 3925);
WIRE 16 -1 (-5150 1975)(-6575 1975);
WIRE 16 -1 (-7700 3925)(-7700 4050);
WIRE 16 -1 (-7750 3925)(-7700 3925);
WIRE 16 -1 (-7750 3750)(-7750 3925);
WIRE 16 -1 (-8000 3925)(-7750 3925);
WIRE 16 -1 (-4500 2025)(-3300 2025);
FORCEPROP 2 LAST SIG_NAME JTAG_SCM_MUX_R_TDO
J 0
(-4400 2035);
DISPLAY 0.489362 (-4400 2035);
FORCEPROP 2 LASTPROP $XRERR UNIQUE?
J 0
(-4640 2035);
DISPLAY 0.638298 (-4640 2035);
PAINT MONO (-4640 2035);
DISPLAY INVISIBLE (-4640 2035);
WIRE 16 -1 (-3100 2025)(-2025 2025);
FORCEPROP 2 LAST SIG_NAME JTAG_SCM_MUX_TDO
J 0
(-2850 2035);
DISPLAY 0.489362 (-2850 2035);
WIRE 16 -1 (-3100 4225)(-2025 4225);
FORCEPROP 2 LAST SIG_NAME JTAG_SCM_MUX_TCK
J 0
(-2875 4235);
DISPLAY 0.489362 (-2875 4235);
WIRE 16 -1 (-3100 3975)(-2025 3975);
FORCEPROP 2 LAST SIG_NAME JTAG_SCM_MUX_TMS
J 0
(-2875 3985);
DISPLAY 0.489362 (-2875 3985);
WIRE 16 -1 (-3100 2275)(-2025 2275);
FORCEPROP 2 LAST SIG_NAME JTAG_SCM_MUX_TDI
J 0
(-2850 2285);
DISPLAY 0.489362 (-2850 2285);
WIRE 16 -1 (-5200 3875)(-6025 3875);
FORCEPROP 2 LAST SIG_NAME SCM_JTAG_MUX_S0_R1
J 0
(-5810 3885);
DISPLAY 0.489362 (-5810 3885);
FORCEPROP 2 LASTPROP $XRERR UNIQUE?
J 0
(-6050 3885);
DISPLAY 0.638298 (-6050 3885);
PAINT MONO (-6050 3885);
DISPLAY INVISIBLE (-6050 3885);
WIRE 16 -1 (-8000 1925)(-7750 1925);
WIRE 16 -1 (-7750 1925)(-7700 1925);
WIRE 16 -1 (-7750 1750)(-7750 1925);
WIRE 16 -1 (-7700 1925)(-7700 2050);
WIRE 16 -1 (-7700 1925)(-6700 1925);
FORCEPROP 2 LAST SIG_NAME SCM_JTAG_MUX_S0
J 0
(-7160 1935);
DISPLAY 0.489362 (-7160 1935);
WIRE 16 -1 (-6700 3875)(-6700 1925);
WIRE 16 -1 (-6700 1925)(-6275 1925);
WIRE 16 -1 (-6225 3875)(-6700 3875);
WIRE 16 -1 (-4550 3925)(-3300 3925);
FORCEPROP 2 LAST SIG_NAME TP_JTAG_SCM_SLOT3_R_TMS
J 0
(-4400 3935);
DISPLAY 0.489362 (-4400 3935);
FORCEPROP 2 LASTPROP $XRERR UNIQUE?
J 0
(-3270 3925);
DISPLAY 0.638298 (-3270 3925);
PAINT MONO (-3270 3925);
DISPLAY INVISIBLE (-3270 3925);
WIRE 16 -1 (-7575 5225)(-8025 5225);
WIRE 16 -1 (-8025 5225)(-8025 5125);
WIRE 16 -1 (-8025 5225)(-8950 5225);
FORCEPROP 2 LAST SIG_NAME FW_RECOVERY_R
J 0
(-8685 5250);
DISPLAY 0.489362 (-8685 5250);
WIRE 16 -1 (-3100 2325)(-2025 2325);
FORCEPROP 2 LAST SIG_NAME JTAG_SCM_PLD_TDI
J 0
(-2850 2335);
DISPLAY 0.489362 (-2850 2335);
WIRE 16 -1 (-4550 4025)(-3850 4025);
FORCEPROP 2 LAST SIG_NAME JTAG_SCM_PLD_R_TMS
J 0
(-4400 4035);
DISPLAY 0.489362 (-4400 4035);
FORCEPROP 2 LASTPROP $XRERR UNIQUE?
J 0
(-4640 4035);
DISPLAY 0.638298 (-4640 4035);
PAINT MONO (-4640 4035);
DISPLAY INVISIBLE (-4640 4035);
WIRE 16 -1 (-3850 4025)(-3300 4025);
WIRE 16 -1 (-3850 4075)(-3850 4025);
WIRE 16 -1 (-4550 4075)(-3850 4075);
WIRE 16 -1 (-3125 5950)(-3125 5750);
WIRE 16 -1 (-3125 5750)(-4125 5750);
FORCEPROP 2 LAST SIG_NAME JTAG_SCM_TMS
J 0
(-4060 5760);
DISPLAY 0.489362 (-4060 5760);
WIRE 16 -1 (-2875 5950)(-2875 5700);
WIRE 16 -1 (-2875 5650)(-2875 5700);
WIRE 16 -1 (-2875 5700)(-4125 5700);
FORCEPROP 2 LAST SIG_NAME JTAG_SCM_TCK
J 0
(-4060 5710);
DISPLAY 0.489362 (-4060 5710);
WIRE 16 -1 (-3325 5950)(-3325 5800);
WIRE 16 -1 (-3325 5800)(-4125 5800);
FORCEPROP 2 LAST SIG_NAME JTAG_SCM_TDI
J 0
(-4060 5810);
DISPLAY 0.489362 (-4060 5810);
WIRE 16 -1 (-450 5925)(-450 5675);
WIRE 16 -1 (-450 5625)(-450 5675);
WIRE 16 -1 (-450 5675)(-1950 5675);
FORCEPROP 2 LAST SIG_NAME JTAG_SCM_MUX_TCK
J 0
(-1885 5685);
DISPLAY 0.489362 (-1885 5685);
WIRE 16 -1 (-4125 5850)(-3525 5850);
FORCEPROP 2 LAST SIG_NAME JTAG_SCM_TDO
J 0
(-4060 5860);
DISPLAY 0.489362 (-4060 5860);
WIRE 16 -1 (-3525 5850)(-3525 5950);
WIRE 16 -1 (-4900 1150)(-5400 1150);
FORCEPROP 2 LAST SIG_NAME PD_U212_EN_N
J 0
(-5335 1160);
DISPLAY 0.680851 (-5335 1160);
FORCEPROP 2 LASTPROP $XRERR UNIQUE?
J 0
(-5575 1160);
DISPLAY 0.638298 (-5575 1160);
PAINT MONO (-5575 1160);
DISPLAY INVISIBLE (-5575 1160);
WIRE 16 -1 (-5400 1150)(-5400 1100);
WIRE 16 -1 (-3100 4025)(-2025 4025);
FORCEPROP 2 LAST SIG_NAME JTAG_SCM_PLD_TMS
J 0
(-2885 4035);
DISPLAY 0.489362 (-2885 4035);
WIRE 16 -1 (-5875 2325)(-5150 2325);
FORCEPROP 2 LAST SIG_NAME JTAG_SCM_TDI
J 0
(-5785 2335);
DISPLAY 0.489362 (-5785 2335);
WIRE 16 -1 (-6075 1925)(-5150 1925);
FORCEPROP 2 LAST SIG_NAME SCM_JTAG_MUX_S0_R2
J 0
(-5785 1935);
DISPLAY 0.489362 (-5785 1935);
FORCEPROP 2 LASTPROP $XRERR UNIQUE?
J 0
(-6025 1935);
DISPLAY 0.638298 (-6025 1935);
PAINT MONO (-6025 1935);
DISPLAY INVISIBLE (-6025 1935);
WIRE 16 -1 (-3100 2075)(-2025 2075);
FORCEPROP 2 LAST SIG_NAME JTAG_SCM_PLD_TDO
J 0
(-2850 2085);
DISPLAY 0.489362 (-2850 2085);
WIRE 16 -1 (-3850 3100)(-4225 3100);
FORCEPROP 2 LAST SIG_NAME PD_U160_EN_N
J 0
(-4235 3110);
DISPLAY 0.680851 (-4235 3110);
FORCEPROP 2 LASTPROP $XRERR UNIQUE?
J 0
(-4475 3110);
DISPLAY 0.638298 (-4475 3110);
PAINT MONO (-4475 3110);
DISPLAY INVISIBLE (-4475 3110);
WIRE 16 -1 (-4225 3100)(-4225 3000);
WIRE 16 -1 (-5850 4275)(-5200 4275);
FORCEPROP 2 LAST SIG_NAME JTAG_SCM_TCK
J 0
(-5760 4285);
DISPLAY 0.489362 (-5760 4285);
WIRE 16 -1 (-5850 4075)(-5200 4075);
FORCEPROP 2 LAST SIG_NAME JTAG_SCM_TMS
J 0
(-5760 4085);
DISPLAY 0.489362 (-5760 4085);
WIRE 16 -1 (-4550 4275)(-3825 4275);
FORCEPROP 2 LAST SIG_NAME JTAG_SCM_PLD_R_TCK
J 0
(-4400 4285);
DISPLAY 0.489362 (-4400 4285);
FORCEPROP 2 LASTPROP $XRERR UNIQUE?
J 0
(-4640 4285);
DISPLAY 0.638298 (-4640 4285);
PAINT MONO (-4640 4285);
DISPLAY INVISIBLE (-4640 4285);
WIRE 16 -1 (-3825 4275)(-3300 4275);
WIRE 16 -1 (-3825 4325)(-3825 4275);
WIRE 16 -1 (-4550 4325)(-3825 4325);
DOT 1 (-6575 5225);
DOT 1 (-8025 5225);
DOT 1 (-8000 5700);
DOT 1 (-3525 6250);
DOT 1 (-875 6225);
DOT 1 (-450 5675);
DOT 1 (-675 6225);
DOT 1 (-7700 1925);
DOT 1 (-7750 1925);
DOT 1 (-6700 1925);
DOT 1 (-7700 3925);
DOT 1 (-7750 3925);
DOT 1 (-6575 3925);
DOT 1 (-5350 4750);
DOT 1 (-1075 6225);
DOT 1 (-3325 6250);
DOT 1 (-3125 6250);
DOT 1 (-2875 5700);
DOT 1 (-4475 3775);
DOT 1 (-3725 2325);
DOT 1 (-3775 2075);
DOT 1 (-3850 4025);
DOT 1 (-4425 1825);
DOT 1 (-5350 2800);
DOT 1 (-3825 4275);
CIRCLE (-4700 850)(-4520 850);
PAINT YELLOW (-4700 850);
CIRCLE (-3625 2800)(-3445 2800);
PAINT YELLOW (-3625 2800);
FORCENOTE
CPU
(-500 925) 0;
DISPLAY LEFT (-500 925);
DISPLAY 1.574468 (-500 925);
PAINT MONO (-500 925);
FORCENOTE
CPLD
(-500 625) 0;
DISPLAY LEFT (-500 625);
DISPLAY 1.574468 (-500 625);
PAINT MONO (-500 625);
FORCENOTE
CPLD
(-500 775) 0;
DISPLAY LEFT (-500 775);
DISPLAY 1.574468 (-500 775);
PAINT MONO (-500 775);
FORCENOTE
RSVD
(-500 1100) 0;
DISPLAY LEFT (-500 1100);
DISPLAY 1.574468 (-500 1100);
PAINT MONO (-500 1100);
FORCENOTE
TBC
(-4775 825) 0;
DISPLAY LEFT (-4775 825);
DISPLAY 1.021277 (-4775 825);
FORCENOTE
2-3 ENABLE
(-6375 850) 0;
DISPLAY LEFT (-6375 850);
DISPLAY 1.021277 (-6375 850);
FORCENOTE
1-2 DISABLE(DEFAULT)
(-6375 925) 0;
DISPLAY LEFT (-6375 925);
DISPLAY 1.021277 (-6375 925);
FORCENOTE
JTAG ENABLE JUMPER
(-6375 1000) 0;
DISPLAY LEFT (-6375 1000);
DISPLAY 1.021277 (-6375 1000);
FORCENOTE
TBC
(-3700 2775) 0;
DISPLAY LEFT (-3700 2775);
DISPLAY 1.021277 (-3700 2775);
FORCENOTE
2-3 ENABLE
(-3450 3025) 0;
DISPLAY LEFT (-3450 3025);
DISPLAY 1.021277 (-3450 3025);
FORCENOTE
1-2 DISABLE(DEFAULT)
(-3450 3100) 0;
DISPLAY LEFT (-3450 3100);
DISPLAY 1.021277 (-3450 3100);
FORCENOTE
JTAG ENABLE JUMPER
(-3450 3175) 0;
DISPLAY LEFT (-3450 3175);
DISPLAY 1.021277 (-3450 3175);
FORCENOTE
$CDS_IMAGE|table.jpg|3544|1096
(-2350 950) 0;
DISPLAY LEFT (-2350 950);
QUIT
